(kicad_sch
	(version 20250114)
	(generator "eeschema")
	(generator_version "9.0")
	(paper "A3")
	(title_block
		(title "Antmicro Baseboard for Jetson AGX Thor")
		(date "2026-02-17")
		(rev "1.1.0")
		(company "Antmicro Ltd")
		(comment 1 "www.antmicro.com")
	)
	(bus_alias "USBSS"
		(members "TX+" "TX-" "RX+" "RX-")
	)
	(text "SoM\n"
		(exclude_from_sim no)
		(at 215.9 25.4 0)
		(effects
			(font
				(size 1.905 1.905)
			)
		)
	)
	(junction
		(at 381 213.36)
		(diameter 0)
		(color 0 0 0 0)
	)
	(junction
		(at 381 226.06)
		(diameter 0)
		(color 0 0 0 0)
	)
	(junction
		(at 381 238.76)
		(diameter 0)
		(color 0 0 0 0)
	)
	(junction
		(at 260.35 203.2)
		(diameter 0)
		(color 0 0 0 0)
	)
	(junction
		(at 381 219.71)
		(diameter 0)
		(color 0 0 0 0)
	)
	(junction
		(at 157.48 135.89)
		(diameter 0)
		(color 0 0 0 0)
	)
	(junction
		(at 381 245.11)
		(diameter 0)
		(color 0 0 0 0)
	)
	(junction
		(at 381 232.41)
		(diameter 0)
		(color 0 0 0 0)
	)
	(junction
		(at 116.84 88.9)
		(diameter 0)
		(color 0 0 0 0)
	)
	(bus
		(pts
			(xy 100.33 196.85) (xy 177.8 196.85)
		)
		(stroke
			(width 0)
			(type default)
		)
	)
	(wire
		(pts
			(xy 381 213.36) (xy 381 219.71)
		)
		(stroke
			(width 0)
			(type default)
		)
	)
	(wire
		(pts
			(xy 110.49 228.6) (xy 110.49 241.3)
		)
		(stroke
			(width 0)
			(type default)
		)
	)
	(bus
		(pts
			(xy 331.47 181.61) (xy 318.77 181.61)
		)
		(stroke
			(width 0)
			(type default)
		)
	)
	(wire
		(pts
			(xy 271.78 234.95) (xy 331.47 234.95)
		)
		(stroke
			(width 0)
			(type default)
		)
	)
	(wire
		(pts
			(xy 137.16 153.67) (xy 137.16 129.54)
		)
		(stroke
			(width 0)
			(type default)
		)
	)
	(wire
		(pts
			(xy 254 208.28) (xy 274.32 208.28)
		)
		(stroke
			(width 0)
			(type default)
		)
	)
	(bus
		(pts
			(xy 312.42 179.07) (xy 331.47 179.07)
		)
		(stroke
			(width 0)
			(type default)
			(color 194 194 0 1)
		)
	)
	(wire
		(pts
			(xy 100.33 168.91) (xy 177.8 168.91)
		)
		(stroke
			(width 0)
			(type default)
		)
	)
	(bus
		(pts
			(xy 279.4 203.2) (xy 279.4 227.33)
		)
		(stroke
			(width 0)
			(type default)
		)
	)
	(wire
		(pts
			(xy 132.08 158.75) (xy 132.08 134.62)
		)
		(stroke
			(width 0)
			(type default)
		)
	)
	(bus
		(pts
			(xy 157.48 222.25) (xy 331.47 222.25)
		)
		(stroke
			(width 0)
			(type default)
		)
	)
	(wire
		(pts
			(xy 381 245.11) (xy 382.27 245.11)
		)
		(stroke
			(width 0)
			(type default)
		)
	)
	(wire
		(pts
			(xy 331.47 166.37) (xy 322.58 166.37)
		)
		(stroke
			(width 0)
			(type default)
		)
	)
	(wire
		(pts
			(xy 304.8 196.85) (xy 304.8 148.59)
		)
		(stroke
			(width 0)
			(type default)
		)
	)
	(bus
		(pts
			(xy 100.33 176.53) (xy 177.8 176.53)
		)
		(stroke
			(width 0)
			(type default)
			(color 194 194 0 1)
		)
	)
	(bus
		(pts
			(xy 177.8 147.32) (xy 147.32 147.32)
		)
		(stroke
			(width 0)
			(type default)
		)
	)
	(bus
		(pts
			(xy 100.33 76.2) (xy 177.8 76.2)
		)
		(stroke
			(width 0)
			(type default)
			(color 194 0 194 1)
		)
	)
	(wire
		(pts
			(xy 116.84 88.9) (xy 116.84 270.51)
		)
		(stroke
			(width 0)
			(type default)
		)
	)
	(wire
		(pts
			(xy 320.04 168.91) (xy 320.04 140.97)
		)
		(stroke
			(width 0)
			(type default)
		)
	)
	(bus
		(pts
			(xy 100.33 36.83) (xy 177.8 36.83)
		)
		(stroke
			(width 0)
			(type default)
			(color 0 255 0 1)
		)
	)
	(wire
		(pts
			(xy 327.66 148.59) (xy 331.47 148.59)
		)
		(stroke
			(width 0)
			(type default)
		)
	)
	(wire
		(pts
			(xy 100.33 233.68) (xy 105.41 233.68)
		)
		(stroke
			(width 0)
			(type default)
		)
	)
	(bus
		(pts
			(xy 254 118.11) (xy 331.47 118.11)
		)
		(stroke
			(width 0)
			(type default)
			(color 0 194 194 1)
		)
	)
	(wire
		(pts
			(xy 331.47 128.27) (xy 293.37 128.27)
		)
		(stroke
			(width 0)
			(type default)
		)
	)
	(bus
		(pts
			(xy 127 156.21) (xy 127 111.76)
		)
		(stroke
			(width 0)
			(type default)
			(color 132 0 0 1)
		)
	)
	(bus
		(pts
			(xy 177.8 138.43) (xy 154.94 138.43)
		)
		(stroke
			(width 0)
			(type default)
		)
	)
	(wire
		(pts
			(xy 290.83 95.25) (xy 290.83 143.51)
		)
		(stroke
			(width 0)
			(type default)
		)
	)
	(wire
		(pts
			(xy 121.92 256.54) (xy 100.33 256.54)
		)
		(stroke
			(width 0)
			(type default)
		)
	)
	(bus
		(pts
			(xy 124.46 109.22) (xy 124.46 153.67)
		)
		(stroke
			(width 0)
			(type default)
			(color 132 0 0 1)
		)
	)
	(bus
		(pts
			(xy 254 195.58) (xy 287.02 195.58)
		)
		(stroke
			(width 0)
			(type default)
		)
	)
	(bus
		(pts
			(xy 100.33 184.15) (xy 113.03 184.15)
		)
		(stroke
			(width 0)
			(type default)
		)
	)
	(wire
		(pts
			(xy 100.33 231.14) (xy 107.95 231.14)
		)
		(stroke
			(width 0)
			(type default)
		)
	)
	(wire
		(pts
			(xy 331.47 133.35) (xy 307.34 133.35)
		)
		(stroke
			(width 0)
			(type default)
		)
	)
	(bus
		(pts
			(xy 254 36.83) (xy 331.47 36.83)
		)
		(stroke
			(width 0)
			(type default)
			(color 0 255 255 1)
		)
	)
	(wire
		(pts
			(xy 381 219.71) (xy 381 226.06)
		)
		(stroke
			(width 0)
			(type default)
		)
	)
	(bus
		(pts
			(xy 331.47 212.09) (xy 318.77 212.09)
		)
		(stroke
			(width 0)
			(type default)
		)
	)
	(wire
		(pts
			(xy 331.47 95.25) (xy 290.83 95.25)
		)
		(stroke
			(width 0)
			(type default)
		)
	)
	(wire
		(pts
			(xy 294.64 267.97) (xy 294.64 186.69)
		)
		(stroke
			(width 0)
			(type default)
		)
	)
	(bus
		(pts
			(xy 100.33 54.61) (xy 157.48 54.61)
		)
		(stroke
			(width 0)
			(type default)
		)
	)
	(wire
		(pts
			(xy 274.32 232.41) (xy 274.32 208.28)
		)
		(stroke
			(width 0)
			(type default)
		)
	)
	(wire
		(pts
			(xy 290.83 143.51) (xy 254 143.51)
		)
		(stroke
			(width 0)
			(type default)
		)
	)
	(bus
		(pts
			(xy 100.33 119.38) (xy 177.8 119.38)
		)
		(stroke
			(width 0)
			(type default)
			(color 255 0 0 1)
		)
	)
	(wire
		(pts
			(xy 293.37 146.05) (xy 254 146.05)
		)
		(stroke
			(width 0)
			(type default)
		)
	)
	(wire
		(pts
			(xy 274.32 232.41) (xy 331.47 232.41)
		)
		(stroke
			(width 0)
			(type default)
		)
	)
	(wire
		(pts
			(xy 322.58 166.37) (xy 322.58 143.51)
		)
		(stroke
			(width 0)
			(type default)
		)
	)
	(bus
		(pts
			(xy 100.33 219.71) (xy 111.76 219.71)
		)
		(stroke
			(width 0)
			(type default)
		)
	)
	(wire
		(pts
			(xy 119.38 259.08) (xy 119.38 267.97)
		)
		(stroke
			(width 0)
			(type default)
		)
	)
	(wire
		(pts
			(xy 317.5 138.43) (xy 317.5 171.45)
		)
		(stroke
			(width 0)
			(type default)
		)
	)
	(bus
		(pts
			(xy 157.48 54.61) (xy 157.48 135.89)
		)
		(stroke
			(width 0)
			(type default)
		)
	)
	(bus
		(pts
			(xy 100.33 39.37) (xy 177.8 39.37)
		)
		(stroke
			(width 0)
			(type default)
			(color 0 255 0 1)
		)
	)
	(wire
		(pts
			(xy 331.47 92.71) (xy 288.29 92.71)
		)
		(stroke
			(width 0)
			(type default)
		)
	)
	(wire
		(pts
			(xy 381 232.41) (xy 381 238.76)
		)
		(stroke
			(width 0)
			(type default)
		)
	)
	(bus
		(pts
			(xy 129.54 158.75) (xy 100.33 158.75)
		)
		(stroke
			(width 0)
			(type default)
			(color 132 0 0 1)
		)
	)
	(wire
		(pts
			(xy 271.78 210.82) (xy 271.78 234.95)
		)
		(stroke
			(width 0)
			(type default)
		)
	)
	(bus
		(pts
			(xy 154.94 57.15) (xy 100.33 57.15)
		)
		(stroke
			(width 0)
			(type default)
		)
	)
	(bus
		(pts
			(xy 139.7 151.13) (xy 139.7 124.46)
		)
		(stroke
			(width 0)
			(type default)
		)
	)
	(bus
		(pts
			(xy 254 76.2) (xy 331.47 76.2)
		)
		(stroke
			(width 0)
			(type default)
			(color 0 194 194 1)
		)
	)
	(bus
		(pts
			(xy 177.8 151.13) (xy 139.7 151.13)
		)
		(stroke
			(width 0)
			(type default)
		)
	)
	(wire
		(pts
			(xy 292.1 184.15) (xy 292.1 265.43)
		)
		(stroke
			(width 0)
			(type default)
		)
	)
	(bus
		(pts
			(xy 287.02 195.58) (xy 287.02 217.17)
		)
		(stroke
			(width 0)
			(type default)
		)
	)
	(bus
		(pts
			(xy 121.92 106.68) (xy 177.8 106.68)
		)
		(stroke
			(width 0)
			(type default)
			(color 194 0 194 1)
		)
	)
	(wire
		(pts
			(xy 381 207.01) (xy 382.27 207.01)
		)
		(stroke
			(width 0)
			(type default)
		)
	)
	(bus
		(pts
			(xy 127 111.76) (xy 177.8 111.76)
		)
		(stroke
			(width 0)
			(type default)
			(color 132 0 0 1)
		)
	)
	(wire
		(pts
			(xy 119.38 267.97) (xy 294.64 267.97)
		)
		(stroke
			(width 0)
			(type default)
		)
	)
	(bus
		(pts
			(xy 331.47 58.42) (xy 312.42 58.42)
		)
		(stroke
			(width 0)
			(type default)
			(color 194 194 0 1)
		)
	)
	(bus
		(pts
			(xy 100.33 151.13) (xy 121.92 151.13)
		)
		(stroke
			(width 0)
			(type default)
			(color 194 0 194 1)
		)
	)
	(polyline
		(pts
			(xy 269.24 261.62) (xy 269.24 21.59)
		)
		(stroke
			(width 0)
			(type dash)
		)
	)
	(wire
		(pts
			(xy 177.8 153.67) (xy 137.16 153.67)
		)
		(stroke
			(width 0)
			(type default)
		)
	)
	(bus
		(pts
			(xy 171.45 218.44) (xy 171.45 209.55)
		)
		(stroke
			(width 0)
			(type default)
		)
	)
	(wire
		(pts
			(xy 254 205.74) (xy 276.86 205.74)
		)
		(stroke
			(width 0)
			(type default)
		)
	)
	(bus
		(pts
			(xy 129.54 114.3) (xy 129.54 158.75)
		)
		(stroke
			(width 0)
			(type default)
			(color 132 0 0 1)
		)
	)
	(bus
		(pts
			(xy 260.35 203.2) (xy 279.4 203.2)
		)
		(stroke
			(width 0)
			(type default)
		)
	)
	(bus
		(pts
			(xy 121.92 106.68) (xy 121.92 151.13)
		)
		(stroke
			(width 0)
			(type default)
			(color 194 0 194 1)
		)
	)
	(wire
		(pts
			(xy 105.41 233.68) (xy 105.41 246.38)
		)
		(stroke
			(width 0)
			(type default)
		)
	)
	(wire
		(pts
			(xy 116.84 270.51) (xy 297.18 270.51)
		)
		(stroke
			(width 0)
			(type default)
		)
	)
	(bus
		(pts
			(xy 100.33 86.36) (xy 177.8 86.36)
		)
		(stroke
			(width 0)
			(type default)
			(color 0 194 194 1)
		)
	)
	(bus
		(pts
			(xy 254 203.2) (xy 260.35 203.2)
		)
		(stroke
			(width 0)
			(type default)
		)
	)
	(bus
		(pts
			(xy 312.42 58.42) (xy 312.42 179.07)
		)
		(stroke
			(width 0)
			(type default)
			(color 194 194 0 1)
		)
	)
	(bus
		(pts
			(xy 147.32 147.32) (xy 147.32 96.52)
		)
		(stroke
			(width 0)
			(type default)
		)
	)
	(wire
		(pts
			(xy 134.62 156.21) (xy 177.8 156.21)
		)
		(stroke
			(width 0)
			(type default)
		)
	)
	(wire
		(pts
			(xy 297.18 270.51) (xy 297.18 191.77)
		)
		(stroke
			(width 0)
			(type default)
		)
	)
	(bus
		(pts
			(xy 100.33 148.59) (xy 119.38 148.59)
		)
		(stroke
			(width 0)
			(type default)
			(color 194 0 194 1)
		)
	)
	(bus
		(pts
			(xy 124.46 153.67) (xy 100.33 153.67)
		)
		(stroke
			(width 0)
			(type default)
			(color 132 0 0 1)
		)
	)
	(wire
		(pts
			(xy 276.86 229.87) (xy 331.47 229.87)
		)
		(stroke
			(width 0)
			(type default)
		)
	)
	(wire
		(pts
			(xy 288.29 92.71) (xy 288.29 140.97)
		)
		(stroke
			(width 0)
			(type default)
		)
	)
	(wire
		(pts
			(xy 100.33 259.08) (xy 119.38 259.08)
		)
		(stroke
			(width 0)
			(type default)
		)
	)
	(bus
		(pts
			(xy 100.33 186.69) (xy 177.8 186.69)
		)
		(stroke
			(width 0)
			(type default)
		)
	)
	(wire
		(pts
			(xy 325.12 163.83) (xy 325.12 146.05)
		)
		(stroke
			(width 0)
			(type default)
		)
	)
	(bus
		(pts
			(xy 100.33 199.39) (xy 177.8 199.39)
		)
		(stroke
			(width 0)
			(type default)
			(color 128 77 0 1)
		)
	)
	(bus
		(pts
			(xy 331.47 123.19) (xy 318.77 123.19)
		)
		(stroke
			(width 0)
			(type default)
		)
	)
	(wire
		(pts
			(xy 121.92 265.43) (xy 121.92 256.54)
		)
		(stroke
			(width 0)
			(type default)
		)
	)
	(bus
		(pts
			(xy 100.33 44.45) (xy 177.8 44.45)
		)
		(stroke
			(width 0)
			(type default)
			(color 0 255 0 1)
		)
	)
	(wire
		(pts
			(xy 327.66 161.29) (xy 327.66 148.59)
		)
		(stroke
			(width 0)
			(type default)
		)
	)
	(wire
		(pts
			(xy 381 238.76) (xy 382.27 238.76)
		)
		(stroke
			(width 0)
			(type default)
		)
	)
	(wire
		(pts
			(xy 254 210.82) (xy 271.78 210.82)
		)
		(stroke
			(width 0)
			(type default)
		)
	)
	(polyline
		(pts
			(xy 162.56 21.59) (xy 269.24 21.59)
		)
		(stroke
			(width 0)
			(type dash)
		)
	)
	(wire
		(pts
			(xy 381 232.41) (xy 382.27 232.41)
		)
		(stroke
			(width 0)
			(type default)
		)
	)
	(bus
		(pts
			(xy 331.47 55.88) (xy 318.77 55.88)
		)
		(stroke
			(width 0)
			(type default)
		)
	)
	(bus
		(pts
			(xy 100.33 201.93) (xy 177.8 201.93)
		)
		(stroke
			(width 0)
			(type default)
			(color 128 77 0 1)
		)
	)
	(bus
		(pts
			(xy 100.33 204.47) (xy 177.8 204.47)
		)
		(stroke
			(width 0)
			(type default)
			(color 128 77 0 1)
		)
	)
	(wire
		(pts
			(xy 320.04 140.97) (xy 331.47 140.97)
		)
		(stroke
			(width 0)
			(type default)
		)
	)
	(bus
		(pts
			(xy 279.4 227.33) (xy 331.47 227.33)
		)
		(stroke
			(width 0)
			(type default)
		)
	)
	(wire
		(pts
			(xy 254 148.59) (xy 304.8 148.59)
		)
		(stroke
			(width 0)
			(type default)
		)
	)
	(wire
		(pts
			(xy 100.33 166.37) (xy 177.8 166.37)
		)
		(stroke
			(width 0)
			(type default)
		)
	)
	(wire
		(pts
			(xy 137.16 129.54) (xy 100.33 129.54)
		)
		(stroke
			(width 0)
			(type default)
		)
	)
	(wire
		(pts
			(xy 325.12 146.05) (xy 331.47 146.05)
		)
		(stroke
			(width 0)
			(type default)
		)
	)
	(wire
		(pts
			(xy 331.47 138.43) (xy 317.5 138.43)
		)
		(stroke
			(width 0)
			(type default)
		)
	)
	(wire
		(pts
			(xy 307.34 133.35) (xy 307.34 184.15)
		)
		(stroke
			(width 0)
			(type default)
		)
	)
	(wire
		(pts
			(xy 288.29 140.97) (xy 254 140.97)
		)
		(stroke
			(width 0)
			(type default)
		)
	)
	(bus
		(pts
			(xy 119.38 104.14) (xy 177.8 104.14)
		)
		(stroke
			(width 0)
			(type default)
			(color 194 0 194 1)
		)
	)
	(wire
		(pts
			(xy 381 245.11) (xy 381 246.38)
		)
		(stroke
			(width 0)
			(type default)
		)
	)
	(wire
		(pts
			(xy 293.37 128.27) (xy 293.37 146.05)
		)
		(stroke
			(width 0)
			(type default)
		)
	)
	(wire
		(pts
			(xy 283.21 87.63) (xy 283.21 135.89)
		)
		(stroke
			(width 0)
			(type default)
		)
	)
	(wire
		(pts
			(xy 297.18 191.77) (xy 331.47 191.77)
		)
		(stroke
			(width 0)
			(type default)
		)
	)
	(wire
		(pts
			(xy 134.62 132.08) (xy 134.62 156.21)
		)
		(stroke
			(width 0)
			(type default)
		)
	)
	(bus
		(pts
			(xy 254 115.57) (xy 331.47 115.57)
		)
		(stroke
			(width 0)
			(type default)
			(color 0 255 255 1)
		)
	)
	(wire
		(pts
			(xy 381 238.76) (xy 381 245.11)
		)
		(stroke
			(width 0)
			(type default)
		)
	)
	(bus
		(pts
			(xy 100.33 173.99) (xy 177.8 173.99)
		)
		(stroke
			(width 0)
			(type default)
			(color 194 194 0 1)
		)
	)
	(wire
		(pts
			(xy 331.47 196.85) (xy 304.8 196.85)
		)
		(stroke
			(width 0)
			(type default)
		)
	)
	(bus
		(pts
			(xy 100.33 179.07) (xy 177.8 179.07)
		)
		(stroke
			(width 0)
			(type default)
			(color 255 153 0 1)
		)
	)
	(wire
		(pts
			(xy 331.47 168.91) (xy 320.04 168.91)
		)
		(stroke
			(width 0)
			(type default)
		)
	)
	(wire
		(pts
			(xy 276.86 205.74) (xy 276.86 229.87)
		)
		(stroke
			(width 0)
			(type default)
		)
	)
	(wire
		(pts
			(xy 381 213.36) (xy 382.27 213.36)
		)
		(stroke
			(width 0)
			(type default)
		)
	)
	(polyline
		(pts
			(xy 162.56 261.62) (xy 269.24 261.62)
		)
		(stroke
			(width 0)
			(type dash)
		)
	)
	(bus
		(pts
			(xy 139.7 124.46) (xy 100.33 124.46)
		)
		(stroke
			(width 0)
			(type default)
		)
	)
	(bus
		(pts
			(xy 100.33 181.61) (xy 177.8 181.61)
		)
		(stroke
			(width 0)
			(type default)
			(color 255 153 0 1)
		)
	)
	(bus
		(pts
			(xy 157.48 135.89) (xy 157.48 222.25)
		)
		(stroke
			(width 0)
			(type default)
		)
	)
	(bus
		(pts
			(xy 260.35 218.44) (xy 171.45 218.44)
		)
		(stroke
			(width 0)
			(type default)
		)
	)
	(wire
		(pts
			(xy 381 226.06) (xy 382.27 226.06)
		)
		(stroke
			(width 0)
			(type default)
		)
	)
	(wire
		(pts
			(xy 100.33 163.83) (xy 177.8 163.83)
		)
		(stroke
			(width 0)
			(type default)
		)
	)
	(bus
		(pts
			(xy 100.33 189.23) (xy 177.8 189.23)
		)
		(stroke
			(width 0)
			(type default)
		)
	)
	(wire
		(pts
			(xy 294.64 186.69) (xy 331.47 186.69)
		)
		(stroke
			(width 0)
			(type default)
		)
	)
	(wire
		(pts
			(xy 100.33 132.08) (xy 134.62 132.08)
		)
		(stroke
			(width 0)
			(type default)
		)
	)
	(wire
		(pts
			(xy 307.34 184.15) (xy 292.1 184.15)
		)
		(stroke
			(width 0)
			(type default)
		)
	)
	(wire
		(pts
			(xy 283.21 135.89) (xy 254 135.89)
		)
		(stroke
			(width 0)
			(type default)
		)
	)
	(bus
		(pts
			(xy 154.94 57.15) (xy 154.94 138.43)
		)
		(stroke
			(width 0)
			(type default)
		)
	)
	(bus
		(pts
			(xy 331.47 81.28) (xy 318.77 81.28)
		)
		(stroke
			(width 0)
			(type default)
		)
	)
	(bus
		(pts
			(xy 254 110.49) (xy 331.47 110.49)
		)
		(stroke
			(width 0)
			(type default)
			(color 132 0 0 1)
		)
	)
	(wire
		(pts
			(xy 177.8 158.75) (xy 132.08 158.75)
		)
		(stroke
			(width 0)
			(type default)
		)
	)
	(bus
		(pts
			(xy 100.33 78.74) (xy 177.8 78.74)
		)
		(stroke
			(width 0)
			(type default)
			(color 194 0 194 1)
		)
	)
	(wire
		(pts
			(xy 331.47 163.83) (xy 325.12 163.83)
		)
		(stroke
			(width 0)
			(type default)
		)
	)
	(bus
		(pts
			(xy 100.33 171.45) (xy 177.8 171.45)
		)
		(stroke
			(width 0)
			(type default)
			(color 194 194 0 1)
		)
	)
	(bus
		(pts
			(xy 100.33 209.55) (xy 171.45 209.55)
		)
		(stroke
			(width 0)
			(type default)
		)
	)
	(bus
		(pts
			(xy 147.32 96.52) (xy 100.33 96.52)
		)
		(stroke
			(width 0)
			(type default)
		)
	)
	(wire
		(pts
			(xy 317.5 171.45) (xy 331.47 171.45)
		)
		(stroke
			(width 0)
			(type default)
		)
	)
	(wire
		(pts
			(xy 116.84 88.9) (xy 177.8 88.9)
		)
		(stroke
			(width 0)
			(type default)
		)
	)
	(wire
		(pts
			(xy 331.47 90.17) (xy 285.75 90.17)
		)
		(stroke
			(width 0)
			(type default)
		)
	)
	(wire
		(pts
			(xy 100.33 161.29) (xy 177.8 161.29)
		)
		(stroke
			(width 0)
			(type default)
		)
	)
	(wire
		(pts
			(xy 285.75 138.43) (xy 254 138.43)
		)
		(stroke
			(width 0)
			(type default)
		)
	)
	(wire
		(pts
			(xy 331.47 87.63) (xy 283.21 87.63)
		)
		(stroke
			(width 0)
			(type default)
		)
	)
	(wire
		(pts
			(xy 105.41 246.38) (xy 177.8 246.38)
		)
		(stroke
			(width 0)
			(type default)
		)
	)
	(bus
		(pts
			(xy 157.48 135.89) (xy 177.8 135.89)
		)
		(stroke
			(width 0)
			(type default)
		)
	)
	(polyline
		(pts
			(xy 162.56 21.59) (xy 162.56 261.62)
		)
		(stroke
			(width 0)
			(type dash)
		)
	)
	(bus
		(pts
			(xy 254 39.37) (xy 331.47 39.37)
		)
		(stroke
			(width 0)
			(type default)
			(color 0 194 194 1)
		)
	)
	(wire
		(pts
			(xy 132.08 134.62) (xy 100.33 134.62)
		)
		(stroke
			(width 0)
			(type default)
		)
	)
	(wire
		(pts
			(xy 107.95 243.84) (xy 177.8 243.84)
		)
		(stroke
			(width 0)
			(type default)
		)
	)
	(bus
		(pts
			(xy 260.35 203.2) (xy 260.35 218.44)
		)
		(stroke
			(width 0)
			(type default)
		)
	)
	(wire
		(pts
			(xy 381 207.01) (xy 381 213.36)
		)
		(stroke
			(width 0)
			(type default)
		)
	)
	(wire
		(pts
			(xy 322.58 143.51) (xy 331.47 143.51)
		)
		(stroke
			(width 0)
			(type default)
		)
	)
	(wire
		(pts
			(xy 107.95 231.14) (xy 107.95 243.84)
		)
		(stroke
			(width 0)
			(type default)
		)
	)
	(wire
		(pts
			(xy 100.33 228.6) (xy 110.49 228.6)
		)
		(stroke
			(width 0)
			(type default)
		)
	)
	(bus
		(pts
			(xy 100.33 194.31) (xy 177.8 194.31)
		)
		(stroke
			(width 0)
			(type default)
		)
	)
	(bus
		(pts
			(xy 100.33 191.77) (xy 177.8 191.77)
		)
		(stroke
			(width 0)
			(type default)
		)
	)
	(bus
		(pts
			(xy 100.33 41.91) (xy 177.8 41.91)
		)
		(stroke
			(width 0)
			(type default)
			(color 0 255 0 1)
		)
	)
	(wire
		(pts
			(xy 381 219.71) (xy 382.27 219.71)
		)
		(stroke
			(width 0)
			(type default)
		)
	)
	(bus
		(pts
			(xy 254 176.53) (xy 331.47 176.53)
		)
		(stroke
			(width 0)
			(type default)
			(color 255 153 0 1)
		)
	)
	(bus
		(pts
			(xy 177.8 114.3) (xy 129.54 114.3)
		)
		(stroke
			(width 0)
			(type default)
			(color 132 0 0 1)
		)
	)
	(bus
		(pts
			(xy 165.1 184.15) (xy 177.8 184.15)
		)
		(stroke
			(width 0)
			(type default)
		)
	)
	(wire
		(pts
			(xy 292.1 265.43) (xy 121.92 265.43)
		)
		(stroke
			(width 0)
			(type default)
		)
	)
	(bus
		(pts
			(xy 100.33 156.21) (xy 127 156.21)
		)
		(stroke
			(width 0)
			(type default)
			(color 132 0 0 1)
		)
	)
	(bus
		(pts
			(xy 254 73.66) (xy 331.47 73.66)
		)
		(stroke
			(width 0)
			(type default)
			(color 0 255 255 1)
		)
	)
	(bus
		(pts
			(xy 100.33 207.01) (xy 177.8 207.01)
		)
		(stroke
			(width 0)
			(type default)
			(color 128 77 0 1)
		)
	)
	(bus
		(pts
			(xy 119.38 104.14) (xy 119.38 148.59)
		)
		(stroke
			(width 0)
			(type default)
			(color 194 0 194 1)
		)
	)
	(wire
		(pts
			(xy 100.33 88.9) (xy 116.84 88.9)
		)
		(stroke
			(width 0)
			(type default)
		)
	)
	(bus
		(pts
			(xy 287.02 217.17) (xy 331.47 217.17)
		)
		(stroke
			(width 0)
			(type default)
		)
	)
	(wire
		(pts
			(xy 285.75 90.17) (xy 285.75 138.43)
		)
		(stroke
			(width 0)
			(type default)
		)
	)
	(wire
		(pts
			(xy 331.47 161.29) (xy 327.66 161.29)
		)
		(stroke
			(width 0)
			(type default)
		)
	)
	(bus
		(pts
			(xy 177.8 109.22) (xy 124.46 109.22)
		)
		(stroke
			(width 0)
			(type default)
			(color 132 0 0 1)
		)
	)
	(wire
		(pts
			(xy 381 226.06) (xy 381 232.41)
		)
		(stroke
			(width 0)
			(type default)
		)
	)
	(wire
		(pts
			(xy 110.49 241.3) (xy 177.8 241.3)
		)
		(stroke
			(width 0)
			(type default)
		)
	)
	(label "I2C_{SYS}{I2C}"
		(at 113.03 184.15 180)
		(effects
			(font
				(size 1.27 1.27)
			)
			(justify right bottom)
		)
	)
	(label "I2C_{SYS}{I2C}"
		(at 111.76 219.71 180)
		(effects
			(font
				(size 1.27 1.27)
			)
			(justify right bottom)
		)
	)
	(label "I2C_{SYS}{I2C}"
		(at 318.77 55.88 0)
		(effects
			(font
				(size 1.27 1.27)
			)
			(justify left bottom)
		)
	)
	(label "I2C_{SYS}{I2C}"
		(at 318.77 123.19 0)
		(effects
			(font
				(size 1.27 1.27)
			)
			(justify left bottom)
		)
	)
	(label "I2C_{SYS}{I2C}"
		(at 165.1 184.15 0)
		(effects
			(font
				(size 1.27 1.27)
			)
			(justify left bottom)
		)
	)
	(label "I2C_{SYS}{I2C}"
		(at 318.77 212.09 0)
		(effects
			(font
				(size 1.27 1.27)
			)
			(justify left bottom)
		)
	)
	(label "I2C_{SYS}{I2C}"
		(at 318.77 181.61 0)
		(effects
			(font
				(size 1.27 1.27)
			)
			(justify left bottom)
		)
	)
	(label "I2C_{SYS}{I2C}"
		(at 318.77 81.28 0)
		(effects
			(font
				(size 1.27 1.27)
			)
			(justify left bottom)
		)
	)
	(symbol
		(lib_id "antmicroMechanicalParts:Spacer_Drill3.7mm_H8mm_9774080151R")
		(at 382.27 226.06 0)
		(unit 1)
		(exclude_from_sim no)
		(in_bom yes)
		(on_board yes)
		(dnp no)
		(fields_autoplaced yes)
		(property "Reference" "H4"
			(at 391.16 224.79 0)
			(effects
				(font
					(size 1.27 1.27)
					(thickness 0.15)
				)
				(justify left)
			)
		)
		(property "Value" "Spacer_Drill3.7mm_H8mm_9774080151R"
			(at 391.16 227.33 0)
			(effects
				(font
					(size 1.27 1.27)
					(thickness 0.15)
				)
				(justify left)
				(hide yes)
			)
		)
		(property "Footprint" "antmicro-footprints:Spacer_Drill3.7mm_H8mm_9774080151R"
			(at 405.13 233.68 0)
			(effects
				(font
					(size 1.27 1.27)
					(thickness 0.15)
				)
				(justify left bottom)
				(hide yes)
			)
		)
		(property "Datasheet" "https://www.we-online.com/components/products/datasheet/9774080151R.pdf"
			(at 405.13 236.22 0)
			(effects
				(font
					(size 1.27 1.27)
					(thickness 0.15)
				)
				(justify left bottom)
				(hide yes)
			)
		)
		(property "Description" "Spacer, SMT, Non Stop, Steel, Swage Round, 5.1 mm x 8 mm, M2.5 Thread, WA-SMSI Series"
			(at 405.13 248.92 0)
			(effects
				(font
					(size 1.27 1.27)
				)
				(justify left bottom)
				(hide yes)
			)
		)
		(property "Manufacturer" "Würth Elektronik"
			(at 405.13 238.76 0)
			(effects
				(font
					(size 1.27 1.27)
					(thickness 0.15)
				)
				(justify left bottom)
				(hide yes)
			)
		)
		(property "MPN" "9774080151R"
			(at 391.16 227.33 0)
			(effects
				(font
					(size 1.27 1.27)
					(thickness 0.15)
				)
				(justify left)
			)
		)
		(property "Author" "Antmicro"
			(at 405.13 243.84 0)
			(effects
				(font
					(size 1.27 1.27)
					(thickness 0.15)
				)
				(justify left bottom)
				(hide yes)
			)
		)
		(property "License" "Apache-2.0"
			(at 405.13 246.38 0)
			(effects
				(font
					(size 1.27 1.27)
					(thickness 0.15)
				)
				(justify left bottom)
				(hide yes)
			)
		)
		(pin "1"
		)
		(instances
			(project "jetson-agx-thor-baseboard"
				(path ""
					(reference "H4")
					(unit 1)
				)
			)
		)
	)
	(symbol
		(lib_id "antmicroMechanicalParts:Spacer_Drill3.7mm_H8mm_9774080151R")
		(at 382.27 207.01 0)
		(unit 1)
		(exclude_from_sim no)
		(in_bom yes)
		(on_board yes)
		(dnp no)
		(fields_autoplaced yes)
		(property "Reference" "H1"
			(at 391.16 205.74 0)
			(effects
				(font
					(size 1.27 1.27)
					(thickness 0.15)
				)
				(justify left)
			)
		)
		(property "Value" "Spacer_Drill3.7mm_H8mm_9774080151R"
			(at 391.16 208.28 0)
			(effects
				(font
					(size 1.27 1.27)
					(thickness 0.15)
				)
				(justify left)
				(hide yes)
			)
		)
		(property "Footprint" "antmicro-footprints:Spacer_Drill3.7mm_H8mm_9774080151R"
			(at 405.13 214.63 0)
			(effects
				(font
					(size 1.27 1.27)
					(thickness 0.15)
				)
				(justify left bottom)
				(hide yes)
			)
		)
		(property "Datasheet" "https://www.we-online.com/components/products/datasheet/9774080151R.pdf"
			(at 405.13 217.17 0)
			(effects
				(font
					(size 1.27 1.27)
					(thickness 0.15)
				)
				(justify left bottom)
				(hide yes)
			)
		)
		(property "Description" "Spacer, SMT, Non Stop, Steel, Swage Round, 5.1 mm x 8 mm, M2.5 Thread, WA-SMSI Series"
			(at 405.13 229.87 0)
			(effects
				(font
					(size 1.27 1.27)
				)
				(justify left bottom)
				(hide yes)
			)
		)
		(property "Manufacturer" "Würth Elektronik"
			(at 405.13 219.71 0)
			(effects
				(font
					(size 1.27 1.27)
					(thickness 0.15)
				)
				(justify left bottom)
				(hide yes)
			)
		)
		(property "MPN" "9774080151R"
			(at 391.16 208.28 0)
			(effects
				(font
					(size 1.27 1.27)
					(thickness 0.15)
				)
				(justify left)
			)
		)
		(property "Author" "Antmicro"
			(at 405.13 224.79 0)
			(effects
				(font
					(size 1.27 1.27)
					(thickness 0.15)
				)
				(justify left bottom)
				(hide yes)
			)
		)
		(property "License" "Apache-2.0"
			(at 405.13 227.33 0)
			(effects
				(font
					(size 1.27 1.27)
					(thickness 0.15)
				)
				(justify left bottom)
				(hide yes)
			)
		)
		(pin "1"
		)
		(instances
			(project "jetson-agx-thor-baseboard"
				(path ""
					(reference "H1")
					(unit 1)
				)
			)
		)
	)
	(symbol
		(lib_id "antmicroMechanicalParts:Spacer_Drill3.7mm_H8mm_9774080151R")
		(at 382.27 238.76 0)
		(unit 1)
		(exclude_from_sim no)
		(in_bom yes)
		(on_board yes)
		(dnp no)
		(fields_autoplaced yes)
		(property "Reference" "H12"
			(at 391.16 237.49 0)
			(effects
				(font
					(size 1.27 1.27)
					(thickness 0.15)
				)
				(justify left)
			)
		)
		(property "Value" "Spacer_Drill3.7mm_H8mm_9774080151R"
			(at 391.16 240.03 0)
			(effects
				(font
					(size 1.27 1.27)
					(thickness 0.15)
				)
				(justify left)
				(hide yes)
			)
		)
		(property "Footprint" "antmicro-footprints:Spacer_Drill3.7mm_H8mm_9774080151R"
			(at 405.13 246.38 0)
			(effects
				(font
					(size 1.27 1.27)
					(thickness 0.15)
				)
				(justify left bottom)
				(hide yes)
			)
		)
		(property "Datasheet" "https://www.we-online.com/components/products/datasheet/9774080151R.pdf"
			(at 405.13 248.92 0)
			(effects
				(font
					(size 1.27 1.27)
					(thickness 0.15)
				)
				(justify left bottom)
				(hide yes)
			)
		)
		(property "Description" "Spacer, SMT, Non Stop, Steel, Swage Round, 5.1 mm x 8 mm, M2.5 Thread, WA-SMSI Series"
			(at 405.13 261.62 0)
			(effects
				(font
					(size 1.27 1.27)
				)
				(justify left bottom)
				(hide yes)
			)
		)
		(property "Manufacturer" "Würth Elektronik"
			(at 405.13 251.46 0)
			(effects
				(font
					(size 1.27 1.27)
					(thickness 0.15)
				)
				(justify left bottom)
				(hide yes)
			)
		)
		(property "MPN" "9774080151R"
			(at 391.16 240.03 0)
			(effects
				(font
					(size 1.27 1.27)
					(thickness 0.15)
				)
				(justify left)
			)
		)
		(property "Author" "Antmicro"
			(at 405.13 256.54 0)
			(effects
				(font
					(size 1.27 1.27)
					(thickness 0.15)
				)
				(justify left bottom)
				(hide yes)
			)
		)
		(property "License" "Apache-2.0"
			(at 405.13 259.08 0)
			(effects
				(font
					(size 1.27 1.27)
					(thickness 0.15)
				)
				(justify left bottom)
				(hide yes)
			)
		)
		(pin "1"
		)
		(instances
			(project "jetson-agx-thor-baseboard"
				(path ""
					(reference "H12")
					(unit 1)
				)
			)
		)
	)
	(symbol
		(lib_id "antmicropower:GND")
		(at 381 246.38 0)
		(unit 1)
		(exclude_from_sim no)
		(in_bom yes)
		(on_board yes)
		(dnp no)
		(property "Reference" "#PWR01"
			(at 381 252.73 0)
			(effects
				(font
					(size 1.27 1.27)
				)
				(justify left bottom)
				(hide yes)
			)
		)
		(property "Value" "GND"
			(at 381 250.19 0)
			(effects
				(font
					(size 1.27 1.27)
					(thickness 0.15)
				)
			)
		)
		(property "Footprint" ""
			(at 389.89 254 0)
			(effects
				(font
					(size 1.27 1.27)
					(thickness 0.15)
				)
				(justify left bottom)
				(hide yes)
			)
		)
		(property "Datasheet" ""
			(at 389.89 259.08 0)
			(effects
				(font
					(size 1.27 1.27)
					(thickness 0.15)
				)
				(justify left bottom)
				(hide yes)
			)
		)
		(property "Description" ""
			(at 381 246.38 0)
			(effects
				(font
					(size 1.27 1.27)
				)
				(hide yes)
			)
		)
		(property "Author" "Antmicro"
			(at 389.89 254 0)
			(effects
				(font
					(size 1.27 1.27)
					(thickness 0.15)
				)
				(justify left bottom)
				(hide yes)
			)
		)
		(property "License" "Apache-2.0"
			(at 389.89 256.54 0)
			(effects
				(font
					(size 1.27 1.27)
					(thickness 0.15)
				)
				(justify left bottom)
				(hide yes)
			)
		)
		(pin "1"
		)
		(instances
			(project "jetson-agx-thor-baseboard"
				(path ""
					(reference "#PWR01")
					(unit 1)
				)
			)
		)
	)
	(symbol
		(lib_id "antmicroMechanicalParts:Spacer_Drill3.7mm_H8mm_9774080151R")
		(at 382.27 245.11 0)
		(unit 1)
		(exclude_from_sim no)
		(in_bom yes)
		(on_board yes)
		(dnp no)
		(fields_autoplaced yes)
		(property "Reference" "H13"
			(at 391.16 243.84 0)
			(effects
				(font
					(size 1.27 1.27)
					(thickness 0.15)
				)
				(justify left)
			)
		)
		(property "Value" "Spacer_Drill3.7mm_H8mm_9774080151R"
			(at 391.16 246.38 0)
			(effects
				(font
					(size 1.27 1.27)
					(thickness 0.15)
				)
				(justify left)
				(hide yes)
			)
		)
		(property "Footprint" "antmicro-footprints:Spacer_Drill3.7mm_H8mm_9774080151R"
			(at 405.13 252.73 0)
			(effects
				(font
					(size 1.27 1.27)
					(thickness 0.15)
				)
				(justify left bottom)
				(hide yes)
			)
		)
		(property "Datasheet" "https://www.we-online.com/components/products/datasheet/9774080151R.pdf"
			(at 405.13 255.27 0)
			(effects
				(font
					(size 1.27 1.27)
					(thickness 0.15)
				)
				(justify left bottom)
				(hide yes)
			)
		)
		(property "Description" "Spacer, SMT, Non Stop, Steel, Swage Round, 5.1 mm x 8 mm, M2.5 Thread, WA-SMSI Series"
			(at 405.13 267.97 0)
			(effects
				(font
					(size 1.27 1.27)
				)
				(justify left bottom)
				(hide yes)
			)
		)
		(property "Manufacturer" "Würth Elektronik"
			(at 405.13 257.81 0)
			(effects
				(font
					(size 1.27 1.27)
					(thickness 0.15)
				)
				(justify left bottom)
				(hide yes)
			)
		)
		(property "MPN" "9774080151R"
			(at 391.16 246.38 0)
			(effects
				(font
					(size 1.27 1.27)
					(thickness 0.15)
				)
				(justify left)
			)
		)
		(property "Author" "Antmicro"
			(at 405.13 262.89 0)
			(effects
				(font
					(size 1.27 1.27)
					(thickness 0.15)
				)
				(justify left bottom)
				(hide yes)
			)
		)
		(property "License" "Apache-2.0"
			(at 405.13 265.43 0)
			(effects
				(font
					(size 1.27 1.27)
					(thickness 0.15)
				)
				(justify left bottom)
				(hide yes)
			)
		)
		(pin "1"
		)
		(instances
			(project "jetson-agx-thor-baseboard"
				(path ""
					(reference "H13")
					(unit 1)
				)
			)
		)
	)
	(symbol
		(lib_id "antmicroFiducialMarks:Fiducial_1mm_Mask3mm")
		(at 21.59 43.18 0)
		(unit 1)
		(exclude_from_sim no)
		(in_bom no)
		(on_board yes)
		(dnp no)
		(fields_autoplaced yes)
		(property "Reference" "FD4"
			(at 26.67 41.91 0)
			(effects
				(font
					(size 1.27 1.27)
					(thickness 0.15)
				)
				(justify left)
			)
		)
		(property "Value" "Fiducial_1mm_Mask3mm"
			(at 26.67 44.45 0)
			(effects
				(font
					(size 1.27 1.27)
					(thickness 0.15)
				)
				(justify left)
			)
		)
		(property "Footprint" "antmicro-footprints:Fiducial_1mm_Mask3mm"
			(at 29.21 48.26 0)
			(effects
				(font
					(size 1.27 1.27)
					(thickness 0.15)
				)
				(justify left bottom)
				(hide yes)
			)
		)
		(property "Datasheet" ""
			(at 28.905 52.4 0)
			(effects
				(font
					(size 1.27 1.27)
					(thickness 0.15)
				)
				(justify left bottom)
				(hide yes)
			)
		)
		(property "Description" "Fiducial mask"
			(at 29.21 55.88 0)
			(effects
				(font
					(size 1.27 1.27)
				)
				(justify left bottom)
				(hide yes)
			)
		)
		(property "Author" "Antmicro"
			(at 29.21 50.8 0)
			(effects
				(font
					(size 1.27 1.27)
					(thickness 0.15)
				)
				(justify left bottom)
				(hide yes)
			)
		)
		(property "License" "Apache-2.0"
			(at 29.21 53.34 0)
			(effects
				(font
					(size 1.27 1.27)
					(thickness 0.15)
				)
				(justify left bottom)
				(hide yes)
			)
		)
		(instances
			(project "jetson-agx-thor-baseboard"
				(path ""
					(reference "FD4")
					(unit 1)
				)
			)
		)
	)
	(symbol
		(lib_id "antmicroFiducialMarks:Fiducial_1mm_Mask3mm")
		(at 21.59 27.94 0)
		(unit 1)
		(exclude_from_sim no)
		(in_bom no)
		(on_board yes)
		(dnp no)
		(fields_autoplaced yes)
		(property "Reference" "FD2"
			(at 26.67 26.67 0)
			(effects
				(font
					(size 1.27 1.27)
					(thickness 0.15)
				)
				(justify left)
			)
		)
		(property "Value" "Fiducial_1mm_Mask3mm"
			(at 26.67 29.21 0)
			(effects
				(font
					(size 1.27 1.27)
					(thickness 0.15)
				)
				(justify left)
			)
		)
		(property "Footprint" "antmicro-footprints:Fiducial_1mm_Mask3mm"
			(at 29.21 33.02 0)
			(effects
				(font
					(size 1.27 1.27)
					(thickness 0.15)
				)
				(justify left bottom)
				(hide yes)
			)
		)
		(property "Datasheet" ""
			(at 28.905 37.16 0)
			(effects
				(font
					(size 1.27 1.27)
					(thickness 0.15)
				)
				(justify left bottom)
				(hide yes)
			)
		)
		(property "Description" "Fiducial mask"
			(at 29.21 40.64 0)
			(effects
				(font
					(size 1.27 1.27)
				)
				(justify left bottom)
				(hide yes)
			)
		)
		(property "Author" "Antmicro"
			(at 29.21 35.56 0)
			(effects
				(font
					(size 1.27 1.27)
					(thickness 0.15)
				)
				(justify left bottom)
				(hide yes)
			)
		)
		(property "License" "Apache-2.0"
			(at 29.21 38.1 0)
			(effects
				(font
					(size 1.27 1.27)
					(thickness 0.15)
				)
				(justify left bottom)
				(hide yes)
			)
		)
		(instances
			(project "jetson-agx-thor-baseboard"
				(path ""
					(reference "FD2")
					(unit 1)
				)
			)
		)
	)
	(symbol
		(lib_id "antmicroFiducialMarks:Fiducial_1mm_Mask3mm")
		(at 21.59 73.66 0)
		(unit 1)
		(exclude_from_sim no)
		(in_bom no)
		(on_board yes)
		(dnp no)
		(fields_autoplaced yes)
		(property "Reference" "FD8"
			(at 26.67 72.39 0)
			(effects
				(font
					(size 1.27 1.27)
					(thickness 0.15)
				)
				(justify left)
			)
		)
		(property "Value" "Fiducial_1mm_Mask3mm"
			(at 26.67 74.93 0)
			(effects
				(font
					(size 1.27 1.27)
					(thickness 0.15)
				)
				(justify left)
			)
		)
		(property "Footprint" "antmicro-footprints:Fiducial_1mm_Mask3mm"
			(at 29.21 78.74 0)
			(effects
				(font
					(size 1.27 1.27)
					(thickness 0.15)
				)
				(justify left bottom)
				(hide yes)
			)
		)
		(property "Datasheet" ""
			(at 28.905 82.88 0)
			(effects
				(font
					(size 1.27 1.27)
					(thickness 0.15)
				)
				(justify left bottom)
				(hide yes)
			)
		)
		(property "Description" "Fiducial mask"
			(at 29.21 86.36 0)
			(effects
				(font
					(size 1.27 1.27)
				)
				(justify left bottom)
				(hide yes)
			)
		)
		(property "Author" "Antmicro"
			(at 29.21 81.28 0)
			(effects
				(font
					(size 1.27 1.27)
					(thickness 0.15)
				)
				(justify left bottom)
				(hide yes)
			)
		)
		(property "License" "Apache-2.0"
			(at 29.21 83.82 0)
			(effects
				(font
					(size 1.27 1.27)
					(thickness 0.15)
				)
				(justify left bottom)
				(hide yes)
			)
		)
		(instances
			(project "jetson-agx-thor-baseboard"
				(path ""
					(reference "FD8")
					(unit 1)
				)
			)
		)
	)
	(symbol
		(lib_id "antmicroFiducialMarks:Fiducial_1mm_Mask3mm")
		(at 21.59 66.04 0)
		(unit 1)
		(exclude_from_sim no)
		(in_bom no)
		(on_board yes)
		(dnp no)
		(fields_autoplaced yes)
		(property "Reference" "FD7"
			(at 26.67 64.77 0)
			(effects
				(font
					(size 1.27 1.27)
					(thickness 0.15)
				)
				(justify left)
			)
		)
		(property "Value" "Fiducial_1mm_Mask3mm"
			(at 26.67 67.31 0)
			(effects
				(font
					(size 1.27 1.27)
					(thickness 0.15)
				)
				(justify left)
			)
		)
		(property "Footprint" "antmicro-footprints:Fiducial_1mm_Mask3mm"
			(at 29.21 71.12 0)
			(effects
				(font
					(size 1.27 1.27)
					(thickness 0.15)
				)
				(justify left bottom)
				(hide yes)
			)
		)
		(property "Datasheet" ""
			(at 28.905 75.26 0)
			(effects
				(font
					(size 1.27 1.27)
					(thickness 0.15)
				)
				(justify left bottom)
				(hide yes)
			)
		)
		(property "Description" "Fiducial mask"
			(at 29.21 78.74 0)
			(effects
				(font
					(size 1.27 1.27)
				)
				(justify left bottom)
				(hide yes)
			)
		)
		(property "Author" "Antmicro"
			(at 29.21 73.66 0)
			(effects
				(font
					(size 1.27 1.27)
					(thickness 0.15)
				)
				(justify left bottom)
				(hide yes)
			)
		)
		(property "License" "Apache-2.0"
			(at 29.21 76.2 0)
			(effects
				(font
					(size 1.27 1.27)
					(thickness 0.15)
				)
				(justify left bottom)
				(hide yes)
			)
		)
		(instances
			(project "jetson-agx-thor-baseboard"
				(path ""
					(reference "FD7")
					(unit 1)
				)
			)
		)
	)
	(symbol
		(lib_id "antmicroMechanicalParts:Spacer_Drill3.7mm_H8mm_9774080151R")
		(at 382.27 213.36 0)
		(unit 1)
		(exclude_from_sim no)
		(in_bom yes)
		(on_board yes)
		(dnp no)
		(fields_autoplaced yes)
		(property "Reference" "H2"
			(at 391.16 212.09 0)
			(effects
				(font
					(size 1.27 1.27)
					(thickness 0.15)
				)
				(justify left)
			)
		)
		(property "Value" "Spacer_Drill3.7mm_H8mm_9774080151R"
			(at 391.16 214.63 0)
			(effects
				(font
					(size 1.27 1.27)
					(thickness 0.15)
				)
				(justify left)
				(hide yes)
			)
		)
		(property "Footprint" "antmicro-footprints:Spacer_Drill3.7mm_H8mm_9774080151R"
			(at 405.13 220.98 0)
			(effects
				(font
					(size 1.27 1.27)
					(thickness 0.15)
				)
				(justify left bottom)
				(hide yes)
			)
		)
		(property "Datasheet" "https://www.we-online.com/components/products/datasheet/9774080151R.pdf"
			(at 405.13 223.52 0)
			(effects
				(font
					(size 1.27 1.27)
					(thickness 0.15)
				)
				(justify left bottom)
				(hide yes)
			)
		)
		(property "Description" "Spacer, SMT, Non Stop, Steel, Swage Round, 5.1 mm x 8 mm, M2.5 Thread, WA-SMSI Series"
			(at 405.13 236.22 0)
			(effects
				(font
					(size 1.27 1.27)
				)
				(justify left bottom)
				(hide yes)
			)
		)
		(property "Manufacturer" "Würth Elektronik"
			(at 405.13 226.06 0)
			(effects
				(font
					(size 1.27 1.27)
					(thickness 0.15)
				)
				(justify left bottom)
				(hide yes)
			)
		)
		(property "MPN" "9774080151R"
			(at 391.16 214.63 0)
			(effects
				(font
					(size 1.27 1.27)
					(thickness 0.15)
				)
				(justify left)
			)
		)
		(property "Author" "Antmicro"
			(at 405.13 231.14 0)
			(effects
				(font
					(size 1.27 1.27)
					(thickness 0.15)
				)
				(justify left bottom)
				(hide yes)
			)
		)
		(property "License" "Apache-2.0"
			(at 405.13 233.68 0)
			(effects
				(font
					(size 1.27 1.27)
					(thickness 0.15)
				)
				(justify left bottom)
				(hide yes)
			)
		)
		(pin "1"
		)
		(instances
			(project "jetson-agx-thor-baseboard"
				(path ""
					(reference "H2")
					(unit 1)
				)
			)
		)
	)
	(symbol
		(lib_id "antmicroFiducialMarks:Fiducial_1mm_Mask3mm")
		(at 21.59 50.8 0)
		(unit 1)
		(exclude_from_sim no)
		(in_bom no)
		(on_board yes)
		(dnp no)
		(fields_autoplaced yes)
		(property "Reference" "FD5"
			(at 26.67 49.53 0)
			(effects
				(font
					(size 1.27 1.27)
					(thickness 0.15)
				)
				(justify left)
			)
		)
		(property "Value" "Fiducial_1mm_Mask3mm"
			(at 26.67 52.07 0)
			(effects
				(font
					(size 1.27 1.27)
					(thickness 0.15)
				)
				(justify left)
			)
		)
		(property "Footprint" "antmicro-footprints:Fiducial_1mm_Mask3mm"
			(at 29.21 55.88 0)
			(effects
				(font
					(size 1.27 1.27)
					(thickness 0.15)
				)
				(justify left bottom)
				(hide yes)
			)
		)
		(property "Datasheet" ""
			(at 28.905 60.02 0)
			(effects
				(font
					(size 1.27 1.27)
					(thickness 0.15)
				)
				(justify left bottom)
				(hide yes)
			)
		)
		(property "Description" "Fiducial mask"
			(at 29.21 63.5 0)
			(effects
				(font
					(size 1.27 1.27)
				)
				(justify left bottom)
				(hide yes)
			)
		)
		(property "Author" "Antmicro"
			(at 29.21 58.42 0)
			(effects
				(font
					(size 1.27 1.27)
					(thickness 0.15)
				)
				(justify left bottom)
				(hide yes)
			)
		)
		(property "License" "Apache-2.0"
			(at 29.21 60.96 0)
			(effects
				(font
					(size 1.27 1.27)
					(thickness 0.15)
				)
				(justify left bottom)
				(hide yes)
			)
		)
		(instances
			(project "jetson-agx-thor-baseboard"
				(path ""
					(reference "FD5")
					(unit 1)
				)
			)
		)
	)
	(symbol
		(lib_id "antmicroMechanicalParts:Spacer_Drill3.7mm_H8mm_9774080151R")
		(at 382.27 232.41 0)
		(unit 1)
		(exclude_from_sim no)
		(in_bom yes)
		(on_board yes)
		(dnp no)
		(fields_autoplaced yes)
		(property "Reference" "H11"
			(at 391.16 231.14 0)
			(effects
				(font
					(size 1.27 1.27)
					(thickness 0.15)
				)
				(justify left)
			)
		)
		(property "Value" "Spacer_Drill3.7mm_H8mm_9774080151R"
			(at 391.16 233.68 0)
			(effects
				(font
					(size 1.27 1.27)
					(thickness 0.15)
				)
				(justify left)
				(hide yes)
			)
		)
		(property "Footprint" "antmicro-footprints:Spacer_Drill3.7mm_H8mm_9774080151R"
			(at 405.13 240.03 0)
			(effects
				(font
					(size 1.27 1.27)
					(thickness 0.15)
				)
				(justify left bottom)
				(hide yes)
			)
		)
		(property "Datasheet" "https://www.we-online.com/components/products/datasheet/9774080151R.pdf"
			(at 405.13 242.57 0)
			(effects
				(font
					(size 1.27 1.27)
					(thickness 0.15)
				)
				(justify left bottom)
				(hide yes)
			)
		)
		(property "Description" "Spacer, SMT, Non Stop, Steel, Swage Round, 5.1 mm x 8 mm, M2.5 Thread, WA-SMSI Series"
			(at 405.13 255.27 0)
			(effects
				(font
					(size 1.27 1.27)
				)
				(justify left bottom)
				(hide yes)
			)
		)
		(property "Manufacturer" "Würth Elektronik"
			(at 405.13 245.11 0)
			(effects
				(font
					(size 1.27 1.27)
					(thickness 0.15)
				)
				(justify left bottom)
				(hide yes)
			)
		)
		(property "MPN" "9774080151R"
			(at 391.16 233.68 0)
			(effects
				(font
					(size 1.27 1.27)
					(thickness 0.15)
				)
				(justify left)
			)
		)
		(property "Author" "Antmicro"
			(at 405.13 250.19 0)
			(effects
				(font
					(size 1.27 1.27)
					(thickness 0.15)
				)
				(justify left bottom)
				(hide yes)
			)
		)
		(property "License" "Apache-2.0"
			(at 405.13 252.73 0)
			(effects
				(font
					(size 1.27 1.27)
					(thickness 0.15)
				)
				(justify left bottom)
				(hide yes)
			)
		)
		(pin "1"
		)
		(instances
			(project "jetson-agx-thor-baseboard"
				(path ""
					(reference "H11")
					(unit 1)
				)
			)
		)
	)
	(symbol
		(lib_id "antmicroMechanicalParts:Spacer_Drill3.7mm_H8mm_9774080151R")
		(at 382.27 219.71 0)
		(unit 1)
		(exclude_from_sim no)
		(in_bom yes)
		(on_board yes)
		(dnp no)
		(fields_autoplaced yes)
		(property "Reference" "H3"
			(at 391.16 218.44 0)
			(effects
				(font
					(size 1.27 1.27)
					(thickness 0.15)
				)
				(justify left)
			)
		)
		(property "Value" "Spacer_Drill3.7mm_H8mm_9774080151R"
			(at 391.16 220.98 0)
			(effects
				(font
					(size 1.27 1.27)
					(thickness 0.15)
				)
				(justify left)
				(hide yes)
			)
		)
		(property "Footprint" "antmicro-footprints:Spacer_Drill3.7mm_H8mm_9774080151R"
			(at 405.13 227.33 0)
			(effects
				(font
					(size 1.27 1.27)
					(thickness 0.15)
				)
				(justify left bottom)
				(hide yes)
			)
		)
		(property "Datasheet" "https://www.we-online.com/components/products/datasheet/9774080151R.pdf"
			(at 405.13 229.87 0)
			(effects
				(font
					(size 1.27 1.27)
					(thickness 0.15)
				)
				(justify left bottom)
				(hide yes)
			)
		)
		(property "Description" "Spacer, SMT, Non Stop, Steel, Swage Round, 5.1 mm x 8 mm, M2.5 Thread, WA-SMSI Series"
			(at 405.13 242.57 0)
			(effects
				(font
					(size 1.27 1.27)
				)
				(justify left bottom)
				(hide yes)
			)
		)
		(property "Manufacturer" "Würth Elektronik"
			(at 405.13 232.41 0)
			(effects
				(font
					(size 1.27 1.27)
					(thickness 0.15)
				)
				(justify left bottom)
				(hide yes)
			)
		)
		(property "MPN" "9774080151R"
			(at 391.16 220.98 0)
			(effects
				(font
					(size 1.27 1.27)
					(thickness 0.15)
				)
				(justify left)
			)
		)
		(property "Author" "Antmicro"
			(at 405.13 237.49 0)
			(effects
				(font
					(size 1.27 1.27)
					(thickness 0.15)
				)
				(justify left bottom)
				(hide yes)
			)
		)
		(property "License" "Apache-2.0"
			(at 405.13 240.03 0)
			(effects
				(font
					(size 1.27 1.27)
					(thickness 0.15)
				)
				(justify left bottom)
				(hide yes)
			)
		)
		(pin "1"
		)
		(instances
			(project "jetson-agx-thor-baseboard"
				(path ""
					(reference "H3")
					(unit 1)
				)
			)
		)
	)
	(symbol
		(lib_id "antmicroFiducialMarks:Fiducial_1mm_Mask3mm")
		(at 21.59 20.32 0)
		(unit 1)
		(exclude_from_sim no)
		(in_bom no)
		(on_board yes)
		(dnp no)
		(fields_autoplaced yes)
		(property "Reference" "FD1"
			(at 26.67 19.05 0)
			(effects
				(font
					(size 1.27 1.27)
					(thickness 0.15)
				)
				(justify left)
			)
		)
		(property "Value" "Fiducial_1mm_Mask3mm"
			(at 26.67 21.59 0)
			(effects
				(font
					(size 1.27 1.27)
					(thickness 0.15)
				)
				(justify left)
			)
		)
		(property "Footprint" "antmicro-footprints:Fiducial_1mm_Mask3mm"
			(at 29.21 25.4 0)
			(effects
				(font
					(size 1.27 1.27)
					(thickness 0.15)
				)
				(justify left bottom)
				(hide yes)
			)
		)
		(property "Datasheet" ""
			(at 28.905 29.54 0)
			(effects
				(font
					(size 1.27 1.27)
					(thickness 0.15)
				)
				(justify left bottom)
				(hide yes)
			)
		)
		(property "Description" "Fiducial mask"
			(at 29.21 33.02 0)
			(effects
				(font
					(size 1.27 1.27)
				)
				(justify left bottom)
				(hide yes)
			)
		)
		(property "Author" "Antmicro"
			(at 29.21 27.94 0)
			(effects
				(font
					(size 1.27 1.27)
					(thickness 0.15)
				)
				(justify left bottom)
				(hide yes)
			)
		)
		(property "License" "Apache-2.0"
			(at 29.21 30.48 0)
			(effects
				(font
					(size 1.27 1.27)
					(thickness 0.15)
				)
				(justify left bottom)
				(hide yes)
			)
		)
		(instances
			(project ""
				(path ""
					(reference "FD1")
					(unit 1)
				)
			)
		)
	)
	(symbol
		(lib_id "antmicroFiducialMarks:Fiducial_1mm_Mask3mm")
		(at 21.59 35.56 0)
		(unit 1)
		(exclude_from_sim no)
		(in_bom no)
		(on_board yes)
		(dnp no)
		(fields_autoplaced yes)
		(property "Reference" "FD3"
			(at 26.67 34.29 0)
			(effects
				(font
					(size 1.27 1.27)
					(thickness 0.15)
				)
				(justify left)
			)
		)
		(property "Value" "Fiducial_1mm_Mask3mm"
			(at 26.67 36.83 0)
			(effects
				(font
					(size 1.27 1.27)
					(thickness 0.15)
				)
				(justify left)
			)
		)
		(property "Footprint" "antmicro-footprints:Fiducial_1mm_Mask3mm"
			(at 29.21 40.64 0)
			(effects
				(font
					(size 1.27 1.27)
					(thickness 0.15)
				)
				(justify left bottom)
				(hide yes)
			)
		)
		(property "Datasheet" ""
			(at 28.905 44.78 0)
			(effects
				(font
					(size 1.27 1.27)
					(thickness 0.15)
				)
				(justify left bottom)
				(hide yes)
			)
		)
		(property "Description" "Fiducial mask"
			(at 29.21 48.26 0)
			(effects
				(font
					(size 1.27 1.27)
				)
				(justify left bottom)
				(hide yes)
			)
		)
		(property "Author" "Antmicro"
			(at 29.21 43.18 0)
			(effects
				(font
					(size 1.27 1.27)
					(thickness 0.15)
				)
				(justify left bottom)
				(hide yes)
			)
		)
		(property "License" "Apache-2.0"
			(at 29.21 45.72 0)
			(effects
				(font
					(size 1.27 1.27)
					(thickness 0.15)
				)
				(justify left bottom)
				(hide yes)
			)
		)
		(instances
			(project "jetson-agx-thor-baseboard"
				(path ""
					(reference "FD3")
					(unit 1)
				)
			)
		)
	)
	(symbol
		(lib_id "antmicroFiducialMarks:Fiducial_1mm_Mask3mm")
		(at 21.59 58.42 0)
		(unit 1)
		(exclude_from_sim no)
		(in_bom no)
		(on_board yes)
		(dnp no)
		(fields_autoplaced yes)
		(property "Reference" "FD6"
			(at 26.67 57.15 0)
			(effects
				(font
					(size 1.27 1.27)
					(thickness 0.15)
				)
				(justify left)
			)
		)
		(property "Value" "Fiducial_1mm_Mask3mm"
			(at 26.67 59.69 0)
			(effects
				(font
					(size 1.27 1.27)
					(thickness 0.15)
				)
				(justify left)
			)
		)
		(property "Footprint" "antmicro-footprints:Fiducial_1mm_Mask3mm"
			(at 29.21 63.5 0)
			(effects
				(font
					(size 1.27 1.27)
					(thickness 0.15)
				)
				(justify left bottom)
				(hide yes)
			)
		)
		(property "Datasheet" ""
			(at 28.905 67.64 0)
			(effects
				(font
					(size 1.27 1.27)
					(thickness 0.15)
				)
				(justify left bottom)
				(hide yes)
			)
		)
		(property "Description" "Fiducial mask"
			(at 29.21 71.12 0)
			(effects
				(font
					(size 1.27 1.27)
				)
				(justify left bottom)
				(hide yes)
			)
		)
		(property "Author" "Antmicro"
			(at 29.21 66.04 0)
			(effects
				(font
					(size 1.27 1.27)
					(thickness 0.15)
				)
				(justify left bottom)
				(hide yes)
			)
		)
		(property "License" "Apache-2.0"
			(at 29.21 68.58 0)
			(effects
				(font
					(size 1.27 1.27)
					(thickness 0.15)
				)
				(justify left bottom)
				(hide yes)
			)
		)
		(instances
			(project "jetson-agx-thor-baseboard"
				(path ""
					(reference "FD6")
					(unit 1)
				)
			)
		)
	)
	(sheet
		(at 331.47 158.75)
		(size 34.29 40.64)
		(exclude_from_sim no)
		(in_bom yes)
		(on_board yes)
		(dnp no)
		(fields_autoplaced yes)
		(stroke
			(width 0.1524)
			(type solid)
		)
		(fill
			(color 0 0 0 0.0000)
		)
		(property "Sheetname" "USB Debug, PD"
			(at 331.47 158.0384 0)
			(effects
				(font
					(size 1.27 1.27)
				)
				(justify left bottom)
			)
		)
		(property "Sheetfile" "usb_debug_pd.kicad_sch"
			(at 331.47 199.3396 0)
			(effects
				(font
					(size 1.27 1.27)
				)
				(justify left top)
			)
		)
		(pin "I2C_{SYS}{I2C}" input
			(at 331.47 181.61 180)
			(effects
				(font
					(size 1.27 1.27)
				)
				(justify left)
			)
		)
		(pin "SPI_{HUB_DEBUG}{SPI}" input
			(at 331.47 179.07 180)
			(effects
				(font
					(size 1.27 1.27)
				)
				(justify left)
			)
		)
		(pin "UART3_DEBUG{UART}" bidirectional
			(at 331.47 176.53 180)
			(effects
				(font
					(size 1.27 1.27)
				)
				(justify left)
			)
		)
		(pin "USBC1_CTL0" output
			(at 331.47 163.83 180)
			(effects
				(font
					(size 1.27 1.27)
				)
				(justify left)
			)
		)
		(pin "USBC1_CTL1" output
			(at 331.47 161.29 180)
			(effects
				(font
					(size 1.27 1.27)
				)
				(justify left)
			)
		)
		(pin "USBC1_FLIP" output
			(at 331.47 166.37 180)
			(effects
				(font
					(size 1.27 1.27)
				)
				(justify left)
			)
		)
		(pin "USBC_HPD" output
			(at 331.47 171.45 180)
			(effects
				(font
					(size 1.27 1.27)
				)
				(justify left)
			)
		)
		(pin "USBPD2_HV" bidirectional
			(at 331.47 186.69 180)
			(effects
				(font
					(size 1.27 1.27)
				)
				(justify left)
			)
		)
		(pin "~{PDC_I2C1_IRQ}" output
			(at 331.47 196.85 180)
			(effects
				(font
					(size 1.27 1.27)
				)
				(justify left)
			)
		)
		(pin "~{RESET}" input
			(at 331.47 191.77 180)
			(effects
				(font
					(size 1.27 1.27)
				)
				(justify left)
			)
		)
		(pin "USBC1_5V_PEN" output
			(at 331.47 168.91 180)
			(effects
				(font
					(size 1.27 1.27)
				)
				(justify left)
			)
		)
		(instances
			(project "jetson-agx-thor-baseboard"
				(path ""
					(page "9")
				)
			)
		)
	)
	(sheet
		(at 66.04 241.3)
		(size 34.29 21.59)
		(exclude_from_sim no)
		(in_bom yes)
		(on_board yes)
		(dnp no)
		(fields_autoplaced yes)
		(stroke
			(width 0.1524)
			(type solid)
		)
		(fill
			(color 0 0 0 0.0000)
		)
		(property "Sheetname" "Power"
			(at 66.04 240.5884 0)
			(effects
				(font
					(size 1.27 1.27)
				)
				(justify left bottom)
			)
		)
		(property "Sheetfile" "power.kicad_sch"
			(at 66.04 264.1096 0)
			(effects
				(font
					(size 1.27 1.27)
				)
				(justify left top)
			)
		)
		(pin "USBPD1_HV" bidirectional
			(at 100.33 256.54 0)
			(effects
				(font
					(size 1.27 1.27)
				)
				(justify right)
			)
		)
		(pin "USBPD2_HV" bidirectional
			(at 100.33 259.08 0)
			(effects
				(font
					(size 1.27 1.27)
				)
				(justify right)
			)
		)
		(instances
			(project "jetson-agx-thor-baseboard"
				(path ""
					(page "5")
				)
			)
		)
	)
	(sheet
		(at 66.04 216.535)
		(size 34.29 19.05)
		(exclude_from_sim no)
		(in_bom yes)
		(on_board yes)
		(dnp no)
		(fields_autoplaced yes)
		(stroke
			(width 0.1524)
			(type solid)
		)
		(fill
			(color 0 0 0 0.0000)
		)
		(property "Sheetname" "DCDC"
			(at 66.04 215.8234 0)
			(effects
				(font
					(size 1.27 1.27)
				)
				(justify left bottom)
			)
		)
		(property "Sheetfile" "dcdc.kicad_sch"
			(at 66.04 236.1696 0)
			(effects
				(font
					(size 1.27 1.27)
				)
				(justify left top)
			)
		)
		(pin "I2C_{SYS}{I2C}" bidirectional
			(at 100.33 219.71 0)
			(effects
				(font
					(size 1.27 1.27)
				)
				(justify right)
			)
		)
		(pin "~{VDDIN_PWR_BAD}" output
			(at 100.33 233.68 0)
			(effects
				(font
					(size 1.27 1.27)
				)
				(justify right)
			)
		)
		(pin "VIN_PWR_ON" input
			(at 100.33 231.14 0)
			(effects
				(font
					(size 1.27 1.27)
				)
				(justify right)
			)
		)
		(pin "CARRIER_PWR_ON" input
			(at 100.33 228.6 0)
			(effects
				(font
					(size 1.27 1.27)
				)
				(justify right)
			)
		)
		(instances
			(project "jetson-agx-thor-baseboard"
				(path ""
					(page "23")
				)
			)
		)
	)
	(sheet
		(at 177.8 228.6)
		(size 76.2 25.4)
		(exclude_from_sim no)
		(in_bom yes)
		(on_board yes)
		(dnp no)
		(fields_autoplaced yes)
		(stroke
			(width 0.1524)
			(type solid)
		)
		(fill
			(color 0 0 0 0.0000)
		)
		(property "Sheetname" "SoM_Power"
			(at 177.8 227.8884 0)
			(effects
				(font
					(size 1.27 1.27)
				)
				(justify left bottom)
			)
		)
		(property "Sheetfile" "som_power.kicad_sch"
			(at 177.8 254.5846 0)
			(effects
				(font
					(size 1.27 1.27)
				)
				(justify left top)
			)
		)
		(pin "~{VDDIN_PWR_BAD}" input
			(at 177.8 246.38 180)
			(effects
				(font
					(size 1.27 1.27)
				)
				(justify left)
			)
		)
		(pin "VIN_PWR_ON" output
			(at 177.8 243.84 180)
			(effects
				(font
					(size 1.27 1.27)
				)
				(justify left)
			)
		)
		(pin "CARRIER_PWR_ON" output
			(at 177.8 241.3 180)
			(effects
				(font
					(size 1.27 1.27)
				)
				(justify left)
			)
		)
		(instances
			(project "jetson-agx-thor-baseboard"
				(path ""
					(page "4")
				)
			)
		)
	)
	(sheet
		(at 331.47 33.02)
		(size 34.29 27.94)
		(exclude_from_sim no)
		(in_bom yes)
		(on_board yes)
		(dnp no)
		(fields_autoplaced yes)
		(stroke
			(width 0.1524)
			(type solid)
		)
		(fill
			(color 0 0 0 0.0000)
		)
		(property "Sheetname" "USB Hub"
			(at 331.47 32.3084 0)
			(effects
				(font
					(size 1.27 1.27)
				)
				(justify left bottom)
			)
		)
		(property "Sheetfile" "usb_hub.kicad_sch"
			(at 331.47 61.5446 0)
			(effects
				(font
					(size 1.27 1.27)
				)
				(justify left top)
			)
		)
		(pin "I2C_{SYS}{I2C}" bidirectional
			(at 331.47 55.88 180)
			(effects
				(font
					(size 1.27 1.27)
				)
				(justify left)
			)
		)
		(pin "SPI_{HUB_DEBUG}{SPI}" input
			(at 331.47 58.42 180)
			(effects
				(font
					(size 1.27 1.27)
				)
				(justify left)
			)
		)
		(pin "USB2{USB}" bidirectional
			(at 331.47 39.37 180)
			(effects
				(font
					(size 1.27 1.27)
				)
				(justify left)
			)
		)
		(pin "USBSS2{USBSS}" bidirectional
			(at 331.47 36.83 180)
			(effects
				(font
					(size 1.27 1.27)
				)
				(justify left)
			)
		)
		(instances
			(project "jetson-agx-thor-baseboard"
				(path ""
					(page "6")
				)
			)
		)
	)
	(sheet
		(at 66.04 72.39)
		(size 34.29 35.56)
		(exclude_from_sim no)
		(in_bom yes)
		(on_board yes)
		(dnp no)
		(fields_autoplaced yes)
		(stroke
			(width 0.1524)
			(type solid)
		)
		(fill
			(color 0 0 0 0.0000)
		)
		(property "Sheetname" "M.2"
			(at 66.04 71.6784 0)
			(effects
				(font
					(size 1.27 1.27)
				)
				(justify left bottom)
			)
		)
		(property "Sheetfile" "m2.kicad_sch"
			(at 66.04 108.5346 0)
			(effects
				(font
					(size 1.27 1.27)
				)
				(justify left top)
			)
		)
		(pin "~{PEWAKE}" output
			(at 100.33 88.9 0)
			(effects
				(font
					(size 1.27 1.27)
				)
				(justify right)
			)
		)
		(pin "USB3{USB}" bidirectional
			(at 100.33 86.36 0)
			(effects
				(font
					(size 1.27 1.27)
				)
				(justify right)
			)
		)
		(pin "PCIe_{C1x1}{PCIe}" bidirectional
			(at 100.33 76.2 0)
			(effects
				(font
					(size 1.27 1.27)
				)
				(justify right)
			)
		)
		(pin "PCIe_{C5x4}{PCIe}" bidirectional
			(at 100.33 78.74 0)
			(effects
				(font
					(size 1.27 1.27)
				)
				(justify right)
			)
		)
		(pin "M2_E{M2_E}" bidirectional
			(at 100.33 96.52 0)
			(effects
				(font
					(size 1.27 1.27)
				)
				(justify right)
			)
		)
		(instances
			(project "jetson-agx-thor-baseboard"
				(path ""
					(page "12")
				)
			)
		)
	)
	(sheet
		(at 66.04 33.02)
		(size 34.29 30.48)
		(exclude_from_sim no)
		(in_bom yes)
		(on_board yes)
		(dnp no)
		(fields_autoplaced yes)
		(stroke
			(width 0.1524)
			(type solid)
		)
		(fill
			(color 0 0 0 0.0000)
		)
		(property "Sheetname" "CSI"
			(at 66.04 32.3084 0)
			(effects
				(font
					(size 1.27 1.27)
				)
				(justify left bottom)
			)
		)
		(property "Sheetfile" "csi.kicad_sch"
			(at 66.04 63.4496 0)
			(effects
				(font
					(size 1.27 1.27)
				)
				(justify left top)
			)
		)
		(pin "I2C_{CAM}{I2C}" bidirectional
			(at 100.33 57.15 0)
			(effects
				(font
					(size 1.27 1.27)
				)
				(justify right)
			)
		)
		(pin "CAM_CTRL{CAM_CTRL}" bidirectional
			(at 100.33 54.61 0)
			(effects
				(font
					(size 1.27 1.27)
				)
				(justify right)
			)
		)
		(pin "CAM0{CSI}" output
			(at 100.33 36.83 0)
			(effects
				(font
					(size 1.27 1.27)
				)
				(justify right)
			)
		)
		(pin "CAM1{CSI}" output
			(at 100.33 39.37 0)
			(effects
				(font
					(size 1.27 1.27)
				)
				(justify right)
			)
		)
		(pin "CAM2{CSI}" output
			(at 100.33 41.91 0)
			(effects
				(font
					(size 1.27 1.27)
				)
				(justify right)
			)
		)
		(pin "CAM3{CSI}" output
			(at 100.33 44.45 0)
			(effects
				(font
					(size 1.27 1.27)
				)
				(justify right)
			)
		)
		(instances
			(project "jetson-agx-thor-baseboard"
				(path ""
					(page "10")
				)
			)
		)
	)
	(sheet
		(at 177.8 132.08)
		(size 76.2 82.55)
		(exclude_from_sim no)
		(in_bom yes)
		(on_board yes)
		(dnp no)
		(fields_autoplaced yes)
		(stroke
			(width 0.1524)
			(type solid)
		)
		(fill
			(color 0 0 0 0.0000)
		)
		(property "Sheetname" "SoM_IO"
			(at 177.8 131.3684 0)
			(effects
				(font
					(size 1.27 1.27)
				)
				(justify left bottom)
			)
		)
		(property "Sheetfile" "som_io.kicad_sch"
			(at 177.8 215.2146 0)
			(effects
				(font
					(size 1.27 1.27)
				)
				(justify left top)
			)
		)
		(pin "I2C_{CAM}{I2C}" bidirectional
			(at 177.8 138.43 180)
			(effects
				(font
					(size 1.27 1.27)
				)
				(justify left)
			)
		)
		(pin "I2C_{SFP}{I2C}" bidirectional
			(at 177.8 151.13 180)
			(effects
				(font
					(size 1.27 1.27)
				)
				(justify left)
			)
		)
		(pin "MOD_ABS" input
			(at 177.8 158.75 180)
			(effects
				(font
					(size 1.27 1.27)
				)
				(justify left)
			)
		)
		(pin "FAN_PWM" output
			(at 254 208.28 0)
			(effects
				(font
					(size 1.27 1.27)
				)
				(justify right)
			)
		)
		(pin "FAN_TACH" input
			(at 254 210.82 0)
			(effects
				(font
					(size 1.27 1.27)
				)
				(justify right)
			)
		)
		(pin "I2C_{SYS}{I2C}" bidirectional
			(at 177.8 184.15 180)
			(effects
				(font
					(size 1.27 1.27)
				)
				(justify left)
			)
		)
		(pin "I2C_{CONN}{I2C}" bidirectional
			(at 254 195.58 0)
			(effects
				(font
					(size 1.27 1.27)
				)
				(justify right)
			)
		)
		(pin "CAM_CTRL{CAM_CTRL}" bidirectional
			(at 177.8 135.89 180)
			(effects
				(font
					(size 1.27 1.27)
				)
				(justify left)
			)
		)
		(pin "GPIO{GPIO}" bidirectional
			(at 254 203.2 0)
			(effects
				(font
					(size 1.27 1.27)
				)
				(justify right)
			)
		)
		(pin "CAN0{CAN}" bidirectional
			(at 177.8 199.39 180)
			(effects
				(font
					(size 1.27 1.27)
				)
				(justify left)
			)
		)
		(pin "CAN1{CAN}" bidirectional
			(at 177.8 201.93 180)
			(effects
				(font
					(size 1.27 1.27)
				)
				(justify left)
			)
		)
		(pin "I2S2{I2S}" bidirectional
			(at 177.8 194.31 180)
			(effects
				(font
					(size 1.27 1.27)
				)
				(justify left)
			)
		)
		(pin "I2S3{I2S}" bidirectional
			(at 177.8 196.85 180)
			(effects
				(font
					(size 1.27 1.27)
				)
				(justify left)
			)
		)
		(pin "SPI1{SPI}" bidirectional
			(at 177.8 171.45 180)
			(effects
				(font
					(size 1.27 1.27)
				)
				(justify left)
			)
		)
		(pin "SPI2{SPI}" bidirectional
			(at 177.8 173.99 180)
			(effects
				(font
					(size 1.27 1.27)
				)
				(justify left)
			)
		)
		(pin "SPI3{SPI}" bidirectional
			(at 177.8 176.53 180)
			(effects
				(font
					(size 1.27 1.27)
				)
				(justify left)
			)
		)
		(pin "UART2{UART}" bidirectional
			(at 177.8 179.07 180)
			(effects
				(font
					(size 1.27 1.27)
				)
				(justify left)
			)
		)
		(pin "UART5{UART}" bidirectional
			(at 177.8 181.61 180)
			(effects
				(font
					(size 1.27 1.27)
				)
				(justify left)
			)
		)
		(pin "UART3_DEBUG{UART}" bidirectional
			(at 254 176.53 0)
			(effects
				(font
					(size 1.27 1.27)
				)
				(justify right)
			)
		)
		(pin "CAN2{CAN}" bidirectional
			(at 177.8 204.47 180)
			(effects
				(font
					(size 1.27 1.27)
				)
				(justify left)
			)
		)
		(pin "CAN3{CAN}" bidirectional
			(at 177.8 207.01 180)
			(effects
				(font
					(size 1.27 1.27)
				)
				(justify left)
			)
		)
		(pin "I2C0{I2C}" bidirectional
			(at 177.8 186.69 180)
			(effects
				(font
					(size 1.27 1.27)
				)
				(justify left)
			)
		)
		(pin "I2C7{I2C}" bidirectional
			(at 177.8 189.23 180)
			(effects
				(font
					(size 1.27 1.27)
				)
				(justify left)
			)
		)
		(pin "I2C8{I2C}" bidirectional
			(at 177.8 191.77 180)
			(effects
				(font
					(size 1.27 1.27)
				)
				(justify left)
			)
		)
		(pin "USBC1_FLG" input
			(at 254 146.05 0)
			(effects
				(font
					(size 1.27 1.27)
				)
				(justify right)
			)
		)
		(pin "USBC2_PEN" output
			(at 254 138.43 0)
			(effects
				(font
					(size 1.27 1.27)
				)
				(justify right)
			)
		)
		(pin "~{PDC_I2C1_IRQ}" input
			(at 254 148.59 0)
			(effects
				(font
					(size 1.27 1.27)
				)
				(justify right)
			)
		)
		(pin "~{USBC2_INT}" input
			(at 254 140.97 0)
			(effects
				(font
					(size 1.27 1.27)
				)
				(justify right)
			)
		)
		(pin "SFP_LEDG" output
			(at 177.8 153.67 180)
			(effects
				(font
					(size 1.27 1.27)
				)
				(justify left)
			)
		)
		(pin "SFP_LEDY" output
			(at 177.8 156.21 180)
			(effects
				(font
					(size 1.27 1.27)
				)
				(justify left)
			)
		)
		(pin "M2_E{M2_E}" bidirectional
			(at 177.8 147.32 180)
			(effects
				(font
					(size 1.27 1.27)
				)
				(justify left)
			)
		)
		(pin "USBC2_ID" input
			(at 254 135.89 0)
			(effects
				(font
					(size 1.27 1.27)
				)
				(justify right)
			)
		)
		(pin "USBC2_VBUS_DET" input
			(at 254 143.51 0)
			(effects
				(font
					(size 1.27 1.27)
				)
				(justify right)
			)
		)
		(pin "GPIO_EXP_IRQ" input
			(at 254 205.74 0)
			(effects
				(font
					(size 1.27 1.27)
				)
				(justify right)
			)
		)
		(pin "FMC_PG_C2M" bidirectional
			(at 177.8 161.29 180)
			(effects
				(font
					(size 1.27 1.27)
				)
				(justify left)
			)
		)
		(pin "FMC_PG_M2C" bidirectional
			(at 177.8 163.83 180)
			(effects
				(font
					(size 1.27 1.27)
				)
				(justify left)
			)
		)
		(pin "FMC_PRESENT" bidirectional
			(at 177.8 166.37 180)
			(effects
				(font
					(size 1.27 1.27)
				)
				(justify left)
			)
		)
		(pin "FMC_PRSNT_M2C_L" bidirectional
			(at 177.8 168.91 180)
			(effects
				(font
					(size 1.27 1.27)
				)
				(justify left)
			)
		)
		(instances
			(project "jetson-agx-thor-baseboard"
				(path ""
					(page "2")
				)
			)
		)
	)
	(sheet
		(at 66.04 146.05)
		(size 34.29 64.77)
		(exclude_from_sim no)
		(in_bom yes)
		(on_board yes)
		(dnp no)
		(fields_autoplaced yes)
		(stroke
			(width 0.1524)
			(type solid)
		)
		(fill
			(color 0 0 0 0.0000)
		)
		(property "Sheetname" "Expansion connector"
			(at 66.04 145.3384 0)
			(effects
				(font
					(size 1.27 1.27)
				)
				(justify left bottom)
			)
		)
		(property "Sheetfile" "expansion_connector.kicad_sch"
			(at 66.04 211.4046 0)
			(effects
				(font
					(size 1.27 1.27)
				)
				(justify left top)
			)
		)
		(pin "CAN0{CAN}" bidirectional
			(at 100.33 199.39 0)
			(effects
				(font
					(size 1.27 1.27)
				)
				(justify right)
			)
		)
		(pin "CAN1{CAN}" bidirectional
			(at 100.33 201.93 0)
			(effects
				(font
					(size 1.27 1.27)
				)
				(justify right)
			)
		)
		(pin "GPIO{GPIO}" bidirectional
			(at 100.33 209.55 0)
			(effects
				(font
					(size 1.27 1.27)
				)
				(justify right)
			)
		)
		(pin "I2S2{I2S}" bidirectional
			(at 100.33 194.31 0)
			(effects
				(font
					(size 1.27 1.27)
				)
				(justify right)
			)
		)
		(pin "I2S3{I2S}" bidirectional
			(at 100.33 196.85 0)
			(effects
				(font
					(size 1.27 1.27)
				)
				(justify right)
			)
		)
		(pin "PCIe_{C3x2}{PCIe}" bidirectional
			(at 100.33 151.13 0)
			(effects
				(font
					(size 1.27 1.27)
				)
				(justify right)
			)
		)
		(pin "SPI1{SPI}" bidirectional
			(at 100.33 171.45 0)
			(effects
				(font
					(size 1.27 1.27)
				)
				(justify right)
			)
		)
		(pin "SPI2{SPI}" bidirectional
			(at 100.33 173.99 0)
			(effects
				(font
					(size 1.27 1.27)
				)
				(justify right)
			)
		)
		(pin "SPI3{SPI}" bidirectional
			(at 100.33 176.53 0)
			(effects
				(font
					(size 1.27 1.27)
				)
				(justify right)
			)
		)
		(pin "UART2{UART}" bidirectional
			(at 100.33 179.07 0)
			(effects
				(font
					(size 1.27 1.27)
				)
				(justify right)
			)
		)
		(pin "UART5{UART}" bidirectional
			(at 100.33 181.61 0)
			(effects
				(font
					(size 1.27 1.27)
				)
				(justify right)
			)
		)
		(pin "CAN2{CAN}" bidirectional
			(at 100.33 204.47 0)
			(effects
				(font
					(size 1.27 1.27)
				)
				(justify right)
			)
		)
		(pin "CAN3{CAN}" bidirectional
			(at 100.33 207.01 0)
			(effects
				(font
					(size 1.27 1.27)
				)
				(justify right)
			)
		)
		(pin "DP1{DP}" input
			(at 100.33 153.67 0)
			(effects
				(font
					(size 1.27 1.27)
				)
				(justify right)
			)
		)
		(pin "DP2{DP}" input
			(at 100.33 156.21 0)
			(effects
				(font
					(size 1.27 1.27)
				)
				(justify right)
			)
		)
		(pin "DP3{DP}" input
			(at 100.33 158.75 0)
			(effects
				(font
					(size 1.27 1.27)
				)
				(justify right)
			)
		)
		(pin "I2C0{I2C}" bidirectional
			(at 100.33 186.69 0)
			(effects
				(font
					(size 1.27 1.27)
				)
				(justify right)
			)
		)
		(pin "I2C7{I2C}" bidirectional
			(at 100.33 189.23 0)
			(effects
				(font
					(size 1.27 1.27)
				)
				(justify right)
			)
		)
		(pin "I2C8{I2C}" bidirectional
			(at 100.33 191.77 0)
			(effects
				(font
					(size 1.27 1.27)
				)
				(justify right)
			)
		)
		(pin "I2C_{SYS}{I2C}" bidirectional
			(at 100.33 184.15 0)
			(effects
				(font
					(size 1.27 1.27)
				)
				(justify right)
			)
		)
		(pin "PCIe_{C2x1}{PCIe}" bidirectional
			(at 100.33 148.59 0)
			(effects
				(font
					(size 1.27 1.27)
				)
				(justify right)
			)
		)
		(pin "FMC_PG_C2M" bidirectional
			(at 100.33 161.29 0)
			(effects
				(font
					(size 1.27 1.27)
				)
				(justify right)
			)
		)
		(pin "FMC_PG_M2C" bidirectional
			(at 100.33 163.83 0)
			(effects
				(font
					(size 1.27 1.27)
				)
				(justify right)
			)
		)
		(pin "FMC_PRESENT" bidirectional
			(at 100.33 166.37 0)
			(effects
				(font
					(size 1.27 1.27)
				)
				(justify right)
			)
		)
		(pin "FMC_PRSNT_M2C_L" bidirectional
			(at 100.33 168.91 0)
			(effects
				(font
					(size 1.27 1.27)
				)
				(justify right)
			)
		)
		(instances
			(project "jetson-agx-thor-baseboard"
				(path ""
					(page "14")
				)
			)
		)
	)
	(sheet
		(at 177.8 33.02)
		(size 76.2 91.44)
		(exclude_from_sim no)
		(in_bom yes)
		(on_board yes)
		(dnp no)
		(fields_autoplaced yes)
		(stroke
			(width 0.1524)
			(type solid)
		)
		(fill
			(color 0 0 0 0.0000)
		)
		(property "Sheetname" "SoM_IO2"
			(at 177.8 32.3084 0)
			(effects
				(font
					(size 1.27 1.27)
				)
				(justify left bottom)
			)
		)
		(property "Sheetfile" "som_io2.kicad_sch"
			(at 177.8 124.4096 0)
			(effects
				(font
					(size 1.27 1.27)
				)
				(justify left top)
			)
		)
		(pin "PCIe_{C3x2}{PCIe}" bidirectional
			(at 177.8 106.68 180)
			(effects
				(font
					(size 1.27 1.27)
				)
				(justify left)
			)
		)
		(pin "SFI{SFI}" bidirectional
			(at 177.8 119.38 180)
			(effects
				(font
					(size 1.27 1.27)
				)
				(justify left)
			)
		)
		(pin "USB1{USB}" bidirectional
			(at 254 118.11 0)
			(effects
				(font
					(size 1.27 1.27)
				)
				(justify right)
			)
		)
		(pin "~{PEX_WAKE}" passive
			(at 177.8 88.9 180)
			(effects
				(font
					(size 1.27 1.27)
				)
				(justify left)
			)
		)
		(pin "USB0{USB}" bidirectional
			(at 254 76.2 0)
			(effects
				(font
					(size 1.27 1.27)
				)
				(justify right)
			)
		)
		(pin "USBSS0{USBSS}" bidirectional
			(at 254 73.66 0)
			(effects
				(font
					(size 1.27 1.27)
				)
				(justify right)
			)
		)
		(pin "USBSS1{USBSS}" bidirectional
			(at 254 115.57 0)
			(effects
				(font
					(size 1.27 1.27)
				)
				(justify right)
			)
		)
		(pin "USBSS2{USBSS}" bidirectional
			(at 254 36.83 0)
			(effects
				(font
					(size 1.27 1.27)
				)
				(justify right)
			)
		)
		(pin "USB2{USB}" bidirectional
			(at 254 39.37 0)
			(effects
				(font
					(size 1.27 1.27)
				)
				(justify right)
			)
		)
		(pin "USB3{USB}" bidirectional
			(at 177.8 86.36 180)
			(effects
				(font
					(size 1.27 1.27)
				)
				(justify left)
			)
		)
		(pin "DP0{DP}" output
			(at 254 110.49 0)
			(effects
				(font
					(size 1.27 1.27)
				)
				(justify right)
			)
		)
		(pin "DP1{DP}" output
			(at 177.8 109.22 180)
			(effects
				(font
					(size 1.27 1.27)
				)
				(justify left)
			)
		)
		(pin "DP2{DP}" output
			(at 177.8 111.76 180)
			(effects
				(font
					(size 1.27 1.27)
				)
				(justify left)
			)
		)
		(pin "DP3{DP}" output
			(at 177.8 114.3 180)
			(effects
				(font
					(size 1.27 1.27)
				)
				(justify left)
			)
		)
		(pin "PCIe_{C1x1}{PCIe}" input
			(at 177.8 76.2 180)
			(effects
				(font
					(size 1.27 1.27)
				)
				(justify left)
			)
		)
		(pin "PCIe_{C2x1}{PCIe}" bidirectional
			(at 177.8 104.14 180)
			(effects
				(font
					(size 1.27 1.27)
				)
				(justify left)
			)
		)
		(pin "PCIe_{C5x4}{PCIe}" input
			(at 177.8 78.74 180)
			(effects
				(font
					(size 1.27 1.27)
				)
				(justify left)
			)
		)
		(pin "CAM1{CSI}" input
			(at 177.8 39.37 180)
			(effects
				(font
					(size 1.27 1.27)
				)
				(justify left)
			)
		)
		(pin "CAM0{CSI}" input
			(at 177.8 36.83 180)
			(effects
				(font
					(size 1.27 1.27)
				)
				(justify left)
			)
		)
		(pin "CAM2{CSI}" input
			(at 177.8 41.91 180)
			(effects
				(font
					(size 1.27 1.27)
				)
				(justify left)
			)
		)
		(pin "CAM3{CSI}" input
			(at 177.8 44.45 180)
			(effects
				(font
					(size 1.27 1.27)
				)
				(justify left)
			)
		)
		(instances
			(project "jetson-agx-thor-baseboard"
				(path ""
					(page "3")
				)
			)
		)
	)
	(sheet
		(at 331.47 107.95)
		(size 34.29 43.18)
		(exclude_from_sim no)
		(in_bom yes)
		(on_board yes)
		(dnp no)
		(fields_autoplaced yes)
		(stroke
			(width 0.1524)
			(type solid)
		)
		(fill
			(color 0 0 0 0.0000)
		)
		(property "Sheetname" "USB DP Alt mode"
			(at 331.47 107.2384 0)
			(effects
				(font
					(size 1.27 1.27)
				)
				(justify left bottom)
			)
		)
		(property "Sheetfile" "usb_dp.kicad_sch"
			(at 331.47 151.7146 0)
			(effects
				(font
					(size 1.27 1.27)
				)
				(justify left top)
			)
		)
		(pin "DP0{DP}" input
			(at 331.47 110.49 180)
			(effects
				(font
					(size 1.27 1.27)
				)
				(justify left)
			)
		)
		(pin "I2C_{SYS}{I2C}" bidirectional
			(at 331.47 123.19 180)
			(effects
				(font
					(size 1.27 1.27)
				)
				(justify left)
			)
		)
		(pin "USB1{USB}" input
			(at 331.47 118.11 180)
			(effects
				(font
					(size 1.27 1.27)
				)
				(justify left)
			)
		)
		(pin "USBC1_CTL0" input
			(at 331.47 146.05 180)
			(effects
				(font
					(size 1.27 1.27)
				)
				(justify left)
			)
		)
		(pin "USBC1_CTL1" input
			(at 331.47 148.59 180)
			(effects
				(font
					(size 1.27 1.27)
				)
				(justify left)
			)
		)
		(pin "USBC1_FLG" output
			(at 331.47 128.27 180)
			(effects
				(font
					(size 1.27 1.27)
				)
				(justify left)
			)
		)
		(pin "USBC1_FLIP" input
			(at 331.47 143.51 180)
			(effects
				(font
					(size 1.27 1.27)
				)
				(justify left)
			)
		)
		(pin "USBC_HPD" input
			(at 331.47 138.43 180)
			(effects
				(font
					(size 1.27 1.27)
				)
				(justify left)
			)
		)
		(pin "USBPD1_HV" bidirectional
			(at 331.47 133.35 180)
			(effects
				(font
					(size 1.27 1.27)
				)
				(justify left)
			)
		)
		(pin "USBSS1{USBSS}" bidirectional
			(at 331.47 115.57 180)
			(effects
				(font
					(size 1.27 1.27)
				)
				(justify left)
			)
		)
		(pin "USBC1_5V_PEN" input
			(at 331.47 140.97 180)
			(effects
				(font
					(size 1.27 1.27)
				)
				(justify left)
			)
		)
		(instances
			(project "jetson-agx-thor-baseboard"
				(path ""
					(page "8")
				)
			)
		)
	)
	(sheet
		(at 66.04 115.57)
		(size 34.29 22.86)
		(exclude_from_sim no)
		(in_bom yes)
		(on_board yes)
		(dnp no)
		(fields_autoplaced yes)
		(stroke
			(width 0.1524)
			(type solid)
		)
		(fill
			(color 0 0 0 0.0000)
		)
		(property "Sheetname" "SFP"
			(at 66.04 114.8584 0)
			(effects
				(font
					(size 1.27 1.27)
				)
				(justify left bottom)
			)
		)
		(property "Sheetfile" "sfp.kicad_sch"
			(at 66.04 139.0146 0)
			(effects
				(font
					(size 1.27 1.27)
				)
				(justify left top)
			)
		)
		(pin "I2C_{SFP}{I2C}" bidirectional
			(at 100.33 124.46 0)
			(effects
				(font
					(size 1.27 1.27)
				)
				(justify right)
			)
		)
		(pin "MOD_ABS" output
			(at 100.33 134.62 0)
			(effects
				(font
					(size 1.27 1.27)
				)
				(justify right)
			)
		)
		(pin "SFI{SFI}" bidirectional
			(at 100.33 119.38 0)
			(effects
				(font
					(size 1.27 1.27)
				)
				(justify right)
			)
		)
		(pin "SFP_LEDG" input
			(at 100.33 129.54 0)
			(effects
				(font
					(size 1.27 1.27)
				)
				(justify right)
			)
		)
		(pin "SFP_LEDY" input
			(at 100.33 132.08 0)
			(effects
				(font
					(size 1.27 1.27)
				)
				(justify right)
			)
		)
		(instances
			(project "jetson-agx-thor-baseboard"
				(path ""
					(page "11")
				)
			)
		)
	)
	(sheet
		(at 331.47 69.85)
		(size 34.29 29.21)
		(exclude_from_sim no)
		(in_bom yes)
		(on_board yes)
		(dnp no)
		(fields_autoplaced yes)
		(stroke
			(width 0.1524)
			(type solid)
		)
		(fill
			(color 0 0 0 0.0000)
		)
		(property "Sheetname" "Recovery USB"
			(at 331.47 69.1384 0)
			(effects
				(font
					(size 1.27 1.27)
				)
				(justify left bottom)
			)
		)
		(property "Sheetfile" "recovery_usb.kicad_sch"
			(at 331.47 99.0096 0)
			(effects
				(font
					(size 1.27 1.27)
				)
				(justify left top)
			)
		)
		(pin "I2C_{SYS}{I2C}" bidirectional
			(at 331.47 81.28 180)
			(effects
				(font
					(size 1.27 1.27)
				)
				(justify left)
			)
		)
		(pin "USB0{USB}" input
			(at 331.47 76.2 180)
			(effects
				(font
					(size 1.27 1.27)
				)
				(justify left)
			)
		)
		(pin "USBSS0{USBSS}" bidirectional
			(at 331.47 73.66 180)
			(effects
				(font
					(size 1.27 1.27)
				)
				(justify left)
			)
		)
		(pin "~{USBC2_INT}" output
			(at 331.47 92.71 180)
			(effects
				(font
					(size 1.27 1.27)
				)
				(justify left)
			)
		)
		(pin "USBC2_ID" output
			(at 331.47 87.63 180)
			(effects
				(font
					(size 1.27 1.27)
				)
				(justify left)
			)
		)
		(pin "USBC2_PEN" input
			(at 331.47 90.17 180)
			(effects
				(font
					(size 1.27 1.27)
				)
				(justify left)
			)
		)
		(pin "USBC2_VBUS_DET" output
			(at 331.47 95.25 180)
			(effects
				(font
					(size 1.27 1.27)
				)
				(justify left)
			)
		)
		(instances
			(project "jetson-agx-thor-baseboard"
				(path ""
					(page "7")
				)
			)
		)
	)
	(sheet
		(at 331.47 208.28)
		(size 34.29 36.83)
		(exclude_from_sim no)
		(in_bom yes)
		(on_board yes)
		(dnp no)
		(fields_autoplaced yes)
		(stroke
			(width 0.1524)
			(type solid)
		)
		(fill
			(color 0 0 0 0.0000)
		)
		(property "Sheetname" "Peripherals"
			(at 331.47 207.5684 0)
			(effects
				(font
					(size 1.27 1.27)
				)
				(justify left bottom)
			)
		)
		(property "Sheetfile" "peripherals.kicad_sch"
			(at 331.47 245.6946 0)
			(effects
				(font
					(size 1.27 1.27)
				)
				(justify left top)
			)
		)
		(pin "FAN_PWM" input
			(at 331.47 232.41 180)
			(effects
				(font
					(size 1.27 1.27)
				)
				(justify left)
			)
		)
		(pin "FAN_TACH" output
			(at 331.47 234.95 180)
			(effects
				(font
					(size 1.27 1.27)
				)
				(justify left)
			)
		)
		(pin "GPIO{GPIO}" bidirectional
			(at 331.47 227.33 180)
			(effects
				(font
					(size 1.27 1.27)
				)
				(justify left)
			)
		)
		(pin "I2C_{CONN}{I2C}" bidirectional
			(at 331.47 217.17 180)
			(effects
				(font
					(size 1.27 1.27)
				)
				(justify left)
			)
		)
		(pin "I2C_{SYS}{I2C}" input
			(at 331.47 212.09 180)
			(effects
				(font
					(size 1.27 1.27)
				)
				(justify left)
			)
		)
		(pin "CAM_CTRL{CAM_CTRL}" bidirectional
			(at 331.47 222.25 180)
			(effects
				(font
					(size 1.27 1.27)
				)
				(justify left)
			)
		)
		(pin "GPIO_EXP_IRQ" output
			(at 331.47 229.87 180)
			(effects
				(font
					(size 1.27 1.27)
				)
				(justify left)
			)
		)
		(instances
			(project "jetson-agx-thor-baseboard"
				(path ""
					(page "13")
				)
			)
		)
	)
	(sheet_instances
		(path "/"
			(page "1")
		)
	)
)
